# ZAIUS-MB-EVT3-HW-EBOM-X00_20161228-add_2nd_source_X15-20170106-Final.xls — PWA BOM (bom)
| FOXCONN TECHNOLOGY GROUP |  |  |  |  |  |  |  |  |  |  |  |  |  |  |  |  |  |  |  |
| BILL OF MATERIAL |  |  |  |  |  |  |  |  |  |  |  |  |  |  |  |  |  |  |  |
| REV OF  BOM | X15 | CUSTOMER |  | <name> |  | CUSTOMER P/N |  | PWA P/N： | PWA DESCRIPTION |  |  |  | PRODUCT CODE |  |  | PWA  REV |  | DATE |  |
| Sourcing (Single/Sole/Multi) | Critical Commodity (Y or N) | Component Class (1, 2, other) | Customer PSL (Y or N) | Line Item | Item Number | Foxconn P/N | Customer P/N | Part Description | Manufacturer  Full Name | Manufacturer  Part Number | Qty | RoHS Status | Location | CC Qual Build: | Qual by (Customer / ODM ?) | The Date of Change Part or Add 2nd Source | Configuration Identifier | Customer Comments | ODM Comments |
|  |  |  |  | 1 | 1 | 0101EJD00-000-G |  | PCB,Zaius-MB EVT3-X02,OSP,Red,22L,22.20*13.00,G | GCE | 0101EJD00-000-G | 1 |  | PCB |  |  |  |  |  |  |
|  |  |  |  |  | 1 | 0101EJD00-000-G |  | PCB,Zaius-MB EVT3-X02,OSP,Red,22L,22.20*13.00,G | ISU | 0101EJD00-000-G |  |  |  |  |  |  |  |  |  |
|  |  |  |  | 2 | 2 | 890100800-024-G |  | Battery,PANASONIC,CR-2032L/BE,Lithium,3V,225mAH,G | PANASONIC INDUSTRIAL CO.,LTD. | CR-2032L/BE | 1 |  | BAT1 |  |  |  |  |  |  |
|  |  |  |  | 3 | 3 | 622202200-022-G |  | SPET CAP,220uF,+/-20%,10V,105℃,G,SMD2816,ESR<=40mOhm | SANYO ELECTRIC CO., LTD. | 10TPB220ML | 6 |  | CE1,CE4,CE5,CE6,CE33,CE34 |  |  |  |  |  |  |
|  |  |  |  | 4 | 4 | 62120FL00-022-G |  | SPEA CAP,100uF,+/-20%,16V,105℃,G,SMD6.3*5.9,ESR<=24mOhm | SANYO ELECTRIC CO., LTD. | 16SVPC100M | 4 |  | CE17,CE18,CE19,CE20 |  |  |  |  |  |  |
|  |  |  |  | 5 | 5 | 62120BE00-015-G |  | SP-CAP,100uF,+/-20%,16V,105℃,G,SMD2816,ESR<=12mOhm | MURATA ELEC. NORTH AMERICA | ECASD91C107M012K01 | 10 |  | CE21,CE22,CE23,CE24,CE25,CE26,CE27,CE28,CE29,CE30 |  |  |  |  |  |  |
|  |  |  |  | 6 | 6 | 62011U701-015-G |  | CAP,10nF,+/-10%,X7R,6.3V,G,SMD0402 | MURATA ELEC. NORTH AMERICA | GRM155R70J103K | 43 |  | C5,C6,C9,C14,C15,C189,C190,C730,C731,C734,C737,C738,C905,C906,C1513,C1628,C1629,C1630,C1631,C1632,C1633,C1634,C1635,C1636,C1637,C1638,C1639,C1640,C1641,C1642,C1643,C1644,C1667,C1730,C1731,C1732,C1733,C1742,C1743,C1744,C1745,C2048,C2087 |  |  |  |  |  |  |
|  |  |  |  |  | 6 | 62011U700-023-G |  | CAP,10nF,+/-10%,X7R,6.3V,G,SMD0402 | TAIYO ELECTRIC IND.CO.LTD | JMK105B7103KV-F |  |  |  |  |  |  |  |  |  |
|  |  |  |  | 7 | 7 | 620106200-015-G |  | CAP,10nF,+/-10%,X7R,16V,G,SMD0402 | MURATA ELEC. NORTH AMERICA | GRM155R71C103KA01D | 41 |  | PUAC2,PSAC2,PRAC2,PQAC2,PPAC2,PIAC2,PFAC2,PEAC2,PANC7,PBNC8,PBNC15,PANC15,C33,C34,C698,C700,C701,C702,C705,C750,C1714,C1718,C1722,C1726,C2026,C2064,C2065,C2085,C2086,C2088,C2089,C2090,C2091,C2092,C2093,C2094,C2115,C2116,C2120,C2121,C2122 |  |  |  |  |  |  |
|  |  |  |  |  | 7 | 620106200-026-G |  | CAP,10nF,+/-10%,X7R,16V,G,SMD0402 | SAMSUNG SEMICONDUCTOR | CL05B103KO5NNNC |  |  |  |  |  |  |  |  |  |
|  |  |  |  |  | 7 | 620106200-023-G |  | CAP,10nF,+/-10%,X7R,16V,G,SMD0402 | TAIYO ELECTRIC IND.CO.LTD | EMK105B7103KV-F |  |  |  |  |  |  |  |  |  |
|  |  |  |  | 8 | 8 | 620103700-015-G |  | CAP,100nF,+/-10%,X7R,10V,G,SMD0402 | MURATA ELEC. NORTH AMERICA | GRM155R71A104K | 174 |  | PHAC5,PUAC10,PSLC10,PSIC10,PSFC10,PSEC10,PSDC10,PSAC10,PRAC10,PQAC10,PPAC10,PIAC10,PFAC10,PEEC10,PEDC10,PEAC10,C35,C84,C85,C86,C87,C88,C89,C90,C91,C92,C93,C94,C98,C99,C100,C101,C102,C103,C104,C105,C106,C107,C108,C687,C688,C691,C692,C693,C695,C696,C706,C707,C708,C709,C710,C711,C712,C713,C714,C715,C716,C717,C718,C720,C721,C722,C723,C724,C725,C751,C793,C801,C802,C803,C804,C805,C806,C807,C808,C809,C810,C815,C816,C817,C818,C819,C820,C821,C822,C823,C824,C1497,C1498,C1503,C1504,C1691,C1692,C1693,C1694,C1699,C1700,C1701,C1702,C2000,C2001,C2002,C2003,C2021,C2022,C2023,C2024,C2025,C2027,C2034,C2036,C2037,C2038,C2039,C2040,C2042,C2043,C2044,C2045,C2046,C2049,C2050,C2051,C2052,C2053,C2054,C2055,C2056,C2057,C2058,C2059,C2060,C2061,C2062,C2067,C2068,C2073,C2075,C2077,C2078,C2079,C2080,C2083,C2084,C2095,C2096,C2099,C2100,C2101,C2102,C2103,C2104,C2105,C2106,C2117,C2118,C2119,C2123,C2125,C2126,C2127,C2128,C2130,C2133,C2134,C2135,C2142,C2144,C2157,C2158,C2159,C2160,C2161,C2186 |  |  |  |  |  |  |
|  |  |  |  |  | 8 | 620103700-023-G |  | CAP,100nF,+/-10%,X7R,10V,G,SMD0402 | TAIYO ELECTRIC IND.CO.LTD | LMK105B7104KV-F |  |  |  |  |  |  |  |  |  |
|  |  |  |  |  | 8 | 620103700-026-G |  | CAP,100nF,+/-10%,X7R,10V,G,SMD0402 | SAMSUNG SEMICONDUCTOR | CL05B104KP5NNNC |  |  |  |  |  |  |  |  |  |
|  |  |  |  | 9 | 9 | 62010P501-015-G |  | CAP,1nF,+/-10%,X7R,16V,G,SMD0402 | MURATA ELEC. NORTH AMERICA | GRM155R71C102KA01D | 58 |  | C36,C191,C193,C195,C197,C207,C208,C217,C218,C219,C220,C221,C222,C223,C315,C317,C319,C321,C439,C441,C443,C445,C563,C565,C567,C569,C699,C703,C704,C749,C752,C907,C909,C911,C913,C1031,C1033,C1035,C1037,C1155,C1157,C1159,C1161,C1279,C1281,C1283,C1285,C1514,C1517,C1519,C1716,C1720,C1724,C1728,C1947,C1948,C2047,C2124 |  |  |  |  |  |  |
|  |  |  |  |  | 9 | 62010P500-026-G |  | CAP,1nF,+/-10%,X7R,16V,G,SMD0402 | SAMSUNG SEMICONDUCTOR | CL05B102KO5NNNC |  |  |  |  |  |  |  |  |  |
|  |  |  |  |  | 9 | 62010P500-023-G |  | CAP,1nF,+/-10%,X7R,16V,G,SMD0402 | TAIYO ELECTRIC IND.CO.LTD | EMK105B7102KV-F |  |  |  |  |  |  |  |  |  |
|  |  |  |  | 10 | 10 | 62012WD00-015-G |  | CAP,4.7uF,+/-20%,X6S,6.3V,G,SMD0402 | MURATA ELEC. NORTH AMERICA | GRM155C80J475MEAAD | 20 |  | C40,C53,C56,C62,C65,C73,C74,C147,C764,C767,C775,C777,C787,C788,C790,C860,C689,C690,C694,C2166 |  |  |  |  |  |  |
|  |  |  |  |  | 10 | 62012WD00-023-G |  | CAP,4.7uF,+/-20%,X6S,6.3V,G,SMD0402 | TAIYO ELECTRIC IND.CO.LTD | JMK105BC6475MV-F |  |  |  |  |  |  |  |  |  |
|  |  |  |  | 11 | 11 | 62012NU00-015-G |  | CAP,1uF,+/-10%,X7R,6.3V,G,SMD0402 | MURATA ELEC. NORTH AMERICA | GRM155R70J105KA12D | 108 |  | C41,C42,C43,C44,C49,C50,C51,C52,C54,C55,C57,C58,C59,C61,C64,C67,C68,C71,C72,C134,C136,C146,C149,C181,C199,C200,C201,C754,C755,C756,C758,C759,C760,C761,C763,C765,C769,C770,C771,C772,C773,C776,C778,C779,C780,C782,C783,C784,C789,C799,C848,C849,C855,C903,C916,C917,C45,C48,C159,C160,C169,C170,C697,C875,C876,C885,C886,C1475,C1482,C1483,C1500,C1501,C1505,C1506,C1507,C1508,C1509,C1510,C1512,C1572,C1573,C1574,C1575,C1578,C1579,C1580,C1581,C1582,C1583,C1586,C1587,C1588,C1589,C1590,C1591,C1593,C1594,C1595,C1599,C1602,C1605,C1650,C1748,C1833,C2072,C2074,C2076,C2143 |  |  |  |  |  |  |
|  |  |  |  |  | 11 | 62012NU00-026-G |  | CAP,1uF,+/-10%,X7R,6.3V,G,SMD0402 | SAMSUNG SEMICONDUCTOR | CL05B105KQ5NQNC |  |  |  |  |  |  |  |  |  |
|  |  |  |  | 12 | 12 | 62012P100-015-G |  | CAP,2.2uF,+/-20%,X7S,10V,G,SMD0402 | MURATA ELEC. NORTH AMERICA | GRM155C71A225M | 27 |  | PSTC5,PSLC5,PSFC5,PSEC5,PSDC5,PQPC5,PFRC5,PEEC5,PEDC5,C46,C63,C69,C79,C142,C144,C157,C167,C226,C234,C774,C781,C785,C813,C856,C864,C873,C883 |  |  |  |  |  |  |
|  |  |  |  | 13 | 13 | 62011DF01-015-G |  | CAP,220nF,+/-10%,X7R,16V,G,SMD0402 | MURATA ELEC. NORTH AMERICA | GRM155R71C224K | 283 |  | C66,C70,C75,C76,C77,C81,C82,C97,C109,C110,C111,C112,C113,C114,C115,C116,C117,C118,C119,C120,C121,C122,C123,C124,C125,C126,C127,C128,C129,C130,C131,C132,C133,C135,C139,C140,C151,C152,C153,C154,C155,C156,C161,C162,C163,C164,C165,C166,C171,C172,C173,C174,C175,C176,C177,C178,C179,C180,C187,C203,C206,C224,C233,C235,C245,C762,C796,C797,C798,C800,C825,C826,C827,C828,C829,C830,C831,C832,C833,C834,C835,C836,C837,C838,C839,C840,C841,C842,C843,C844,C845,C846,C850,C859,C861,C862,C863,C865,C867,C868,C869,C870,C871,C872,C877,C878,C879,C880,C881,C882,C887,C888,C889,C890,C891,C892,C893,C894,C895,C896,C898,C901,C915,C1753,C1754,C1755,C1756,C1757,C1758,C1759,C1760,C1761,C1762,C1763,C1764,C1765,C1766,C1767,C1768,C1782,C1783,C1784,C1785,C1788,C1789,C1790,C1791,C1792,C1794,C1798,C1799,C1800,C1801,C1802,C1803,C1805,C1806,C1807,C1808,C1809,C1811,C1812,C1813,C1814,C1815,C1819,C1820,C1821,C1822,C1823,C1824,C1826,C1828,C1829,C1830,C1831,C1834,C1835,C1836,C1837,C1838,C1843,C1844,C1845,C1846,C1847,C1848,C1849,C1851,C1852,C1853,C1854,C1855,C1856,C1858,C1859,C1860,C1861,C1862,C1866,C1867,C1868,C1869,C1872,C1873,C1874,C1877,C1878,C1879,C1880,C1881,C1882,C1884,C1888,C1889,C1890,C1891,C1892,C1893,C1895,C1896,C1897,C1898,C1899,C1901,C1902,C1903,C1904,C1905,C1909,C1910,C1911,C1912,C1913,C1914,C1917,C1918,C1919,C1920,C1921,C1922,C1923,C1924,C1925,C1926,C1927,C1928,C1929,C1930,C1931,C1932,C1952,C1953,C1954,C1955,C1956,C1957,C1962,C1963,C1964,C1965,C1966,C1967,C1968,C1969,C1974,C1975,C1984,C1985,C1986,C1987,C1988,C1989,C1990,C1991,C1992,C1993,C1994,C1995,C1996,C1997,C1998,C1999 |  |  |  |  |  |  |
|  |  |  |  |  | 13 | 62011DF00-026-G |  | CAP,220nF,+/-10%,X7R,16V,G,SMD0402 | SAMSUNG SEMICONDUCTOR | CL05B224KO5NNNC |  |  |  |  |  |  |  |  |  |
|  |  |  |  |  | 13 | 62011DF00-023-G |  | CAP,220nF,+/-10%,X7R,16V,G,SMD0402 | TAIYO ELECTRIC IND.CO.LTD | EMK105B7224KV-FR |  |  |  |  |  |  |  |  |  |
|  |  |  |  | 14 | 14 | 62012GF00-015-G |  | CAP,22uF,+/-20%,X6S,6.3V,G,SMD0603 | MURATA ELEC. NORTH AMERICA | GRM188C80J226M | 16 |  | PSPC2,PIPC2,PFPC2,PEPC2,PSPC3,PIPC3,PFPC3,PEPC3,C158,C168,C874,C884,PSPC3000,PIPC3000,PFPC3000,PEPC3000 |  |  |  |  |  |  |
|  |  |  |  |  | 14 | 62012GF00-023-G |  | CAP,22uF,+/-20%,X6S,6.3V,G,SMD0603 | TAIYO ELECTRIC IND.CO.LTD | JDK107BC6226MA-T |  |  |  |  |  |  |  |  |  |
|  |  |  |  | 15 | 15 | 620101T02-015-G |  | CAP,100nF,+/-10%,X7R,16V,G,SMD0402 | MURATA ELEC. NORTH AMERICA | GRM155R71C104K | 235 |  | PSPC1,PIPC1,PFPC1,PEPC1,PSTC10,PQPC10,PFRC10,PETC10,PERC10,PBNC16,PANC16,PBNC17,PANC17,PALC36,PALC41,PALC44,PBLC57,PBLC61,PBLC64,C192,C194,C196,C198,C316,C318,C320,C322,C440,C442,C444,C446,PBFC500,PBEC500,PAFC500,PAEC500,C564,C566,C568,C570,PBMC600,PBAC600,PAMC600,PAAC600,C908,C910,C912,C914,C1032,C1034,C1036,C1038,C1156,C1158,C1160,C1162,C1280,C1282,C1284,C1286,C1403,C1404,C1405,C1406,C1407,C1408,C1409,C1410,C1411,C1412,C1413,C1414,C1415,C1416,C1417,C1418,C1419,C1422,C1423,C1425,C1426,C1428,C1429,C1430,C1431,C1432,C1433,C1434,C1435,C1436,C1437,C1438,C1441,C1442,C1443,C1444,C1445,C1446,C1449,C1450,C1452,C1453,C1454,C1457,C1460,C1461,C1462,C1465,C1467,C1469,C1471,C1472,C1480,C1481,C1484,C1487,C1488,C1490,C1491,C1493,C1494,C1496,C1515,C1516,C1518,C1520,C1521,C1522,C1524,C1526,C1527,C1528,C1529,C1530,C1531,C1534,C1535,C1536,C1537,C1538,C1539,C1540,C1543,C1544,C1545,C1568,C1569,C1570,C1571,C1576,C1597,C1600,C1603,C1606,C1608,C1609,C1610,C1611,C1612,C1613,C1616,C1617,C1618,C1619,C1620,C1621,C1622,C1624,C1625,C1626,C1627,C1645,C1646,C1647,C1648,C1649,C1651,C1652,C1677,C1678,C1713,C1715,C1719,C1723,C1727,C1738,C1740,C1749,C1750,C1787,C1796,C1797,C1841,C1842,C1876,C1886,C1887,C1940,C1941,C1943,C1946,C1949,C1951,C1959,C1960,C1961,C1977,C1978,C1979,C1980,C1981,C1982,C1983,C2004,C2005,C2006,C2007,C2011,C2012,C2029,C2070,C2107,C2108,C2109,C2112,C2131,C2132,C2152,C2155,C2156,C2163,C2164,C2165,C2167,C2181,PSRC3016 |  |  |  |  |  |  |
|  |  |  |  |  | 15 | 620101T00-026-G |  | CAP,100nF,+/-10%,X7R,16V,G,SMD0402 | SAMSUNG SEMICONDUCTOR | CL05B104KO5NNNC |  |  |  |  |  |  |  |  |  |
|  |  |  |  |  | 15 | 620101T00-023-G |  | CAP,100nF,+/-10%,X7R,16V,G,SMD0402 | TAIYO ELECTRIC IND.CO.LTD | EMK105B7104KV-F |  |  |  |  |  |  |  |  |  |
|  |  |  |  | 16 | 16 | 62011KG00-015-G |  | CAP,100nF,+/-5%,X7R,10V,G,SMD0402 | MURATA ELEC. NORTH AMERICA | GRM155R71A104JA01D | 67 |  | C209,C210,C211,C212,C213,C214,C215,C216,C227,C333,C334,C335,C336,C337,C338,C339,C340,C457,C458,C459,C460,C461,C462,C463,C464,C581,C582,C583,C584,C585,C586,C587,C588,C925,C926,C927,C928,C929,C930,C931,C932,C1049,C1050,C1051,C1052,C1053,C1054,C1055,C1056,C1173,C1174,C1175,C1176,C1177,C1178,C1179,C1180,C1297,C1298,C1299,C1300,C1301,C1302,C1303,C1304,C1532,C2009 |  |  |  |  |  |  |
|  |  |  |  |  | 16 | 62011KG00-026-G |  | CAP,100nF,+/-5%,X7R,10V,G,SMD0402 | SAMSUNG SEMICONDUCTOR | CL05B104JP5NNNC |  |  |  |  |  |  |  |  |  |
|  |  |  |  | 17 | 17 | 620135Y00-015-G |  | CAP,2.2uF,+/-20%,X6S,10V,G,SMD0402 | MURATA ELEC. NORTH AMERICA | GRM155C81A225ME15D | 130 |  | PBNC9,PANC9,C237,C238,C239,C240,C247,C248,C249,C250,C265,C266,C267,C268,C283,C284,C285,C286,C361,C362,C363,C364,C371,C372,C373,C374,C389,C390,C391,C392,C407,C408,C409,C410,C485,C486,C487,C488,C495,C496,C497,C498,C513,C514,C515,C516,C531,C532,C533,C534,C609,C610,C611,C612,C619,C620,C621,C622,C637,C638,C639,C640,C655,C656,C657,C658,C953,C954,C955,C956,C963,C964,C965,C966,C981,C982,C983,C984,C999,C1000,C1001,C1002,C1077,C1078,C1079,C1080,C1087,C1088,C1089,C1090,C1105,C1106,C1107,C1108,C1123,C1124,C1125,C1126,C1201,C1202,C1203,C1204,C1211,C1212,C1213,C1214,C1229,C1230,C1231,C1232,C1247,C1248,C1249,C1250,C1325,C1326,C1327,C1328,C1335,C1336,C1337,C1338,C1353,C1354,C1355,C1356,C1371,C1372,C1373,C1374 |  |  |  |  |  |  |
|  |  |  |  | 18 | 18 | 62011SJ00-026-G |  | CAP,470nF,+/-10%,X7R,6.3V,G,SMD0402 | SAMSUNG SEMICONDUCTOR | CL05B474KQ5NNNC | 160 |  | C38,C39,C47,C78,C95,C96,C137,C141,C143,C145,C148,C150,C183,C185,C186,C188,C236,C766,C768,C786,C791,C792,C811,C847,C851,C852,C853,C854,C857,C858,C866,C902,C241,C242,C243,C244,C251,C252,C253,C254,C269,C270,C271,C272,C287,C288,C289,C290,C365,C366,C367,C368,C375,C376,C377,C378,C393,C394,C395,C396,C411,C412,C413,C414,C489,C490,C491,C492,C499,C500,C501,C502,C517,C518,C519,C520,C535,C536,C537,C538,C613,C614,C615,C616,C623,C624,C625,C626,C641,C642,C643,C644,C659,C660,C661,C662,C957,C958,C959,C960,C967,C968,C969,C970,C985,C986,C987,C988,C1003,C1004,C1005,C1006,C1081,C1082,C1083,C1084,C1091,C1092,C1093,C1094,C1109,C1110,C1111,C1112,C1127,C1128,C1129,C1130,C1205,C1206,C1207,C1208,C1215,C1216,C1217,C1218,C1233,C1234,C1235,C1236,C1251,C1252,C1253,C1254,C1329,C1330,C1331,C1332,C1339,C1340,C1341,C1342,C1357,C1358,C1359,C1360,C1375,C1376,C1377,C1378 |  |  |  |  |  |  |
|  |  |  |  |  | 18 | 62011SJ00-023-G |  | CAP,470nF,+/-10%,X7R,6.3V,G,SMD0402 | TAIYO ELECTRIC IND.CO.LTD | JMK105B7474KV-F |  |  |  |  |  |  |  |  |  |
|  |  |  |  | 19 | 19 | 62010MU00-015-G |  | CAP,20pF,+/-5%,NPO(C0G),50V,G,SMD0402 | MURATA ELEC. NORTH AMERICA | GRM1555C1H200J | 6 |  | C1420,C1421,C1476,C1477,C1653,C1654 |  |  |  |  |  |  |
|  |  |  |  |  | 19 | 62010MU00-026-G |  | CAP,20pF,+/-5%,NPO(C0G),50V,G,SMD0402 | SAMSUNG SEMICONDUCTOR | CL05C200JB5NNNC |  |  |  |  |  |  |  |  |  |
|  |  |  |  | 20 | 20 | 620109S00-015-G |  | CAP,4.7uF,+/-10%,X7R,10V,G,SMD0805 | MURATA ELEC. NORTH AMERICA | GRM21BR71A475K | 14 |  | C1424,C1427,C1451,C1455,C1459,C1464,C1466,C1468,C1470,C1499,C1533,C1577,C1585,C1596 |  |  |  |  |  |  |
|  |  |  |  |  | 20 | 620109S00-023-G |  | CAP,4.7uF,+/-10%,X7R,10V,G,SMD0805 | TAIYO ELECTRIC IND.CO.LTD | LMK212B7475KG-T |  |  |  |  |  |  |  |  |  |
|  |  |  |  |  | 20 | 620109S00-026-G |  | CAP,4.7uF,+/-10%,X7R,10V,G,SMD0805 | SAMSUNG SEMICONDUCTOR | CL21B475KPFNNNE |  |  |  |  |  |  |  |  |  |
|  |  |  |  | 21 | 21 | 620109200-015-G |  | CAP,10uF,+/-10%,X7R,6.3V,G,SMD0805 | MURATA ELEC. NORTH AMERICA | GRM21BR70J106K | 7 |  | C1439,C1440,C1447,C1448,C1456,C1623,C1747 |  |  |  |  |  |  |
|  |  |  |  |  | 21 | 620109200-023-G |  | CAP,10uF,+/-10%,X7R,6.3V,G,SMD0805 | TAIYO ELECTRIC IND.CO.LTD | JMK212B7106KG-T |  |  |  |  |  |  |  |  |  |
|  |  |  |  |  | 21 | 620109200-026-G |  | CAP,10uF,+/-10%,X7R,6.3V,G,SMD0805 | SAMSUNG SEMICONDUCTOR | CL21B106KQQNNNE |  |  |  |  |  |  |  |  |  |
|  |  |  |  | 22 | 22 | 620115801-015-G |  | CAP,22uF,+/-10%,X7R,10V,G,SMD1206 | MURATA ELEC. NORTH AMERICA | GRM31CR71A226KE15L | 17 |  | C1458,C1463,C1486,C1489,C1492,C1774,C1775,C1793,C1795,C1839,C1840,C1883,C1885,C1938,C1939,C1950,C1976 |  |  |  |  |  |  |
|  |  |  |  |  | 22 | 620115800-023-G |  | CAP,22uF,+/-10%,X7R,10V,G,SMD1206 | TAIYO ELECTRIC IND.CO.LTD | LMK316B7226KL-TR |  |  |  |  |  |  |  |  |  |
|  |  |  |  |  | 22 | 620115800-026-G |  | CAP,22uF,+/-10%,X7R,10V,G,SMD1206 | SAMSUNG | CL31B226KPHNNNE |  |  |  |  |  |  |  |  |  |
|  |  |  |  | 23 | 23 | 620108000-015-G |  | CAP,100pF,+/-5%,NPO(C0G),50V,G,SMD0402 | MURATA ELEC. NORTH AMERICA | GRM1555C1H101J | 23 |  | PSPC4,PIPC4,PFPC4,PEPC4,PSRC9,PBNC12,PANC12,PSLC14,PSFC14,PSEC14,PSDC14,PEEC14,PEDC14,PBNC14,PANC14,PSIC20,PETC20,PERC20,C1473,C1474,C2041,C2113,C2114 |  |  |  |  |  |  |
|  |  |  |  |  | 23 | 620108000-026-G |  | CAP,100pF,+/-5%,NPO(C0G),50V,G,SMD0402 | SAMSUNG SEMICONDUCTOR | CL05C101JB5NNNC |  |  |  |  |  |  |  |  |  |
|  |  |  |  |  | 23 | 620108000-023-G |  | CAP,100pF,+/-5%,NPO(C0G),50V,G,SMD0402 | TAIYO ELECTRIC IND.CO.LTD | UMK105CG101JV-F |  |  |  |  |  |  |  |  |  |
|  |  |  |  | 24 | 24 | 62010DW00-015-G |  | CAP,10uF,+/-10%,X7R,16V,G,SMD1206 | MURATA ELEC. NORTH AMERICA | GRM31CR71C106K | 11 |  | C1478,C1479,C1485,C1495,C1584,C1778,C1786,C1832,C1875,C1942,C2035 |  |  |  |  |  |  |
|  |  |  |  |  | 24 | 62010DW00-026-G |  | CAP,10uF,+/-10%,X7R,16V,G,SMD1206 | SAMSUNG SEMICONDUCTOR | CL31B106KOHNNNE |  |  |  |  |  |  |  |  |  |
|  |  |  |  |  | 24 | 62010DW00-023-G |  | CAP,10uF,+/-10%,X7R,16V,G,SMD1206 | TAIYO ELECTRIC IND.CO.LTD | EMK316B7106KL-TD |  |  |  |  |  |  |  |  |  |
|  |  |  |  | 25 | 25 | 62010MF00-015-G |  | CAP,100pF,+/-10%,X7R,16V,G,SMD0201 | MURATA ELEC. NORTH AMERICA | GRM033R71C101K | 6 |  | C1502,C1592,C1598,C1601,C1604,C1607 |  |  |  |  |  |  |
|  |  |  |  |  | 25 | 62010MF00-023-G |  | CAP,100pF,+/-10%,X7R,16V,G,SMD0201 | TAIYO ELECTRIC IND.CO.LTD | EMK063B7101KP-F |  |  |  |  |  |  |  |  |  |
|  |  |  |  | 26 | 26 | 62010QB00-015-G |  | CAP,10nF,+/-10%,X7R,50V,G,SMD0402 | MURATA ELEC. NORTH AMERICA | GRM155R71H103K | 13 |  | PSIC7,C1541,C1679,C1680,C1681,C1682,C1684,C1685,C1686,C1688,C1704,C1710,C2069 |  |  |  |  |  |  |
|  |  |  |  |  | 26 | 62010QB00-026-G |  | CAP,10nF,+/-10%,X7R,50V,G,SMD0402 | SAMSUNG SEMICONDUCTOR | CL05B103KB5NNNC |  |  |  |  |  |  |  |  |  |
|  |  |  |  |  | 26 | 62010QB00-023-G |  | CAP,10nF,+/-10%,X7R,50V,G,SMD0402 | TAIYO ELECTRIC IND.CO.LTD | UMK105B7103KV-F |  |  |  |  |  |  |  |  |  |
|  |  |  |  | 27 | 27 | 62010GW00-015-G |  | CAP,10pF,+/-5%,NPO,50V,G,SMD0402 | MURATA ELEC. NORTH AMERICA | GRM1555C1H100J | 1 |  | C1542 |  |  |  |  |  |  |
|  |  |  |  |  | 27 | 620102D00-026-G |  | CAP,10pF,+/-5%,NPO,50V,G,SMD0402 | SAMSUNG | CL05C100JB5NNNC |  |  |  |  |  |  |  |  |  |
|  |  |  |  | 28 | 28 | 62010K200-015-G |  | CAP,12pF,+/-5%,NPO(C0G),50V,G,SMD0402 | MURATA ELEC. NORTH AMERICA | GRM1555C1H120J | 4 |  | C1655,C1656,C2008,C2010 |  |  |  |  |  |  |
|  |  |  |  |  | 28 | 62010K200-023-G |  | CAP,12pF,+/-5%,NPO(C0G),50V,G,SMD0402 | TAIYO ELECTRIC IND.CO.LTD | UMK105CG120JV-F |  |  |  |  |  |  |  |  |  |
|  |  |  |  |  | 28 | 62010K200-026-G |  | CAP,12pF,+/-5%,NPO(C0G),50V,G,SMD0402 | SAMSUNG SEMICONDUCTOR | CL05C120JB5NNNC |  |  |  |  |  |  |  |  |  |
|  |  |  |  | 29 | 29 | 62011D900-015-G |  | CAP,22uF,+/-10%,X7R,6.3V,G,SMD1206 | MURATA ELEC. NORTH AMERICA | GRM31CR70J226K | 1 |  | C1746 |  |  |  |  |  |  |
|  |  |  |  |  | 29 | 62011D900-023-G |  | CAP,22uF,+/-10%,X7R,6.3V,G,SMD1206 | TAIYO ELECTRIC IND.CO.LTD | JMK316B7226KL-T |  |  |  |  |  |  |  |  |  |
|  |  |  |  |  | 29 | 62011D900-026-G |  | CAP,22uF,+/-10%,X7R,6.3V,G,SMD1206 | SAMSUNG SEMICONDUCTOR | CL31B226KQHNNNE |  |  |  |  |  |  |  |  |  |
|  |  |  |  | 30 | 30 | 620100L00-015-G |  | CAP,22pF,+/-5%,NPO(C0G),50V,G,SMD0402 | MURATA ELEC. NORTH AMERICA | GRM1555C1H220J | 14 |  | C1657,C1658,C1659,C1660,C1661,C1662,C1663,C1664,C1665,C1666,C2014,C2016,C2018,C2020 |  |  |  |  |  |  |
|  |  |  |  |  | 30 | 620100L00-023-G |  | CAP,22pF,+/-5%,NPO(C0G),50V,G,SMD0402 | TAIYO ELECTRIC IND.CO.LTD | UMK105CG220JV-F |  |  |  |  |  |  |  |  |  |
|  |  |  |  |  | 30 | 620100L00-026-G |  | CAP,22pF,+/-5%,NPO(C0G),50V,G,SMD0402 | SAMSUNG SEMICONDUCTOR | CL05C220JB5NNNC |  |  |  |  |  |  |  |  |  |
|  |  |  |  | 31 | 31 | 620109N00-015-G |  | CAP,2.2uF,+/-10%,X7R,10V,G,SMD0603 | MURATA ELEC. NORTH AMERICA | GRM188R71A225K | 8 |  | C1683,C1687,C1703,C1709,C1717,C1721,C1725,C1729 |  |  |  |  |  |  |
|  |  |  |  |  | 31 | 620109N00-023-G |  | CAP,2.2uF,+/-10%,X7R,10V,G,SMD0603 | TAIYO ELECTRIC IND.CO.LTD | LMK107B7225KA-T |  |  |  |  |  |  |  |  |  |
|  |  |  |  |  | 31 | 620109N00-026-G |  | CAP,2.2uF,+/-10%,X7R,10V,G,SMD0603 | SAMSUNG SEMICONDUCTOR | CL10B225KP8NNNC |  |  |  |  |  |  |  |  |  |
|  |  |  |  | 32 | 32 | 62012A400-015-G |  | CAP,100nF,+/-10%,X7R,25V,G,SMD0402 | MURATA ELEC. NORTH AMERICA | GRM155R71E104KE14D | 88 |  | PSTC1,PSLC1,PSFC1,PSEC1,PSDC1,PQPC1,PFRC1,PEEC1,PEDC1,PSUC3,PSTC6,PSLC6,PSFC6,PSEC6,PSDC6,PQPC6,PFRC6,PEEC6,PEDC6,PANC6,PBNC7,PBMC10,PBFC10,PBEC10,PBAC10,PAMC10,PAFC10,PAEC10,PAAC10,PSIC21,PETC21,PERC21,PBFC58,PBEC58,PAFC58,PAEC58,PBMC59,PAMC59,PBAC123,PAAC123,C1689,C1695,C1696,C1697,C1698,C1705,C1711,C1770,C1771,C1772,C1773,C1776,C1777,C1779,C1810,C1816,C1817,C1818,C1857,C1863,C1864,C1865,C1900,C1906,C1907,C1908,C1934,C1935,C1936,C1937,C1944,C1945,C1971,C1972,C1973,C2030,C2031,PSPC3002,PIPC3002,PFPC3002,PEPC3002,PSRC3006,PSPC3008,PIPC3008,PFPC3008,PEPC3008,PSRC3009,PSRC3011 |  |  |  |  |  |  |
|  |  |  |  |  | 32 | 62012A400-023-G |  | CAP,100nF,+/-10%,X7R,25V,G,SMD0402 | TAIYO ELECTRIC IND.CO.LTD | TMK105B7104KV-FR |  |  |  |  |  |  |  |  |  |
|  |  |  |  |  | 32 | 62012A400-026-G |  | CAP,100nF,+/-10%,X7R,25V,G,SMD0402 | SAMSUNG SEMICONDUCTOR | CL05B104KA5NNNC |  |  |  |  |  |  |  |  |  |
|  |  |  |  | 33 | 33 | 620103K00-015-G |  | CAP,1nF,+/-10%,X7R,50V,G,SMD0402 | MURATA ELEC. NORTH AMERICA | GRM155R71H102K | 12 |  | PHAC2,PUAC7,PSAC7,PRAC7,PQAC7,PPAC7,PIAC7,PFAC7,PEAC7,C1690,C1706,C1712 |  |  |  |  |  |  |
|  |  |  |  |  | 33 | 620103K00-026-G |  | CAP,1nF,+/-10%,X7R,50V,G,SMD0402 | SAMSUNG SEMICONDUCTOR | CL05B102KB5NNNC |  |  |  |  |  |  |  |  |  |
|  |  |  |  |  | 33 | 620103K00-023-G |  | CAP,1nF,+/-10%,X7R,50V,G,SMD0402 | TAIYO ELECTRIC IND.CO.LTD | UMK105B7102KV-F |  |  |  |  |  |  |  |  |  |
|  |  |  |  | 34 | 34 | 62011KS00-015-G |  | CAP,16pF,+/-5%,NPO(C0G),50V,G,SMD0402 | MURATA ELEC. NORTH AMERICA | GRM1555C1H160JA01D | 2 |  | C1707,C1708 |  |  |  |  |  |  |
|  |  |  |  |  | 34 | 62011KS00-026-G |  | CAP,16pF,+/-5%,NPO(C0G),50V,G,SMD0402 | SAMSUNG SEMICONDUCTOR | CL05C160JB5NNNC |  |  |  |  |  |  |  |  |  |
|  |  |  |  | 35 | 35 | 620112900-015-G |  | CAP,47nF,+/-10%,X7R,25V,G,SMD0402 | MURATA ELEC. NORTH AMERICA | GRM155R71E473K | 4 |  | C1734,C1735,C1736,C1739 |  |  |  |  |  |  |
|  |  |  |  |  | 35 | 620112900-026-G |  | CAP,47nF,+/-10%,X7R,25V,G,SMD0402 | SAMSUNG SEMICONDUCTOR | CL05B473KA5NNNC |  |  |  |  |  |  |  |  |  |
|  |  |  |  |  | 35 | 620112900-023-G |  | CAP,47nF,+/-10%,X7R,25V,G,SMD0402 | TAIYO ELECTRIC IND.CO.LTD | TMK105B7473KV-F |  |  |  |  |  |  |  |  |  |
|  |  |  |  | 36 | 36 | 620103U00-015-G |  | CAP,470pF,+/-10%,X7R,50V,G,SMD0402 | MURATA ELEC. NORTH AMERICA | GRM155R71H471K | 14 |  | PBMC3,PBFC3,PBEC3,PBAC3,PAMC3,PAFC3,PAEC3,PAAC3,PALC42,PALC43,PBLC58,PBLC59,C1737,C1741 |  |  |  |  |  |  |
|  |  |  |  |  | 36 | 620103U00-026-G |  | CAP,470pF,+/-10%,X7R,50V,G,SMD0402 | SAMSUNG SEMICONDUCTOR | CL05B471KB5NNNC |  |  |  |  |  |  |  |  |  |
|  |  |  |  |  | 36 | 620103U00-023-G |  | CAP,470pF,+/-10%,X7R,50V,G,SMD0402 | TAIYO ELECTRIC IND.CO.LTD | UMK105B7471KV-F |  |  |  |  |  |  |  |  |  |
|  |  |  |  | 37 | 37 | 62011HS01-015-G |  | CAP,10uF,+/-10%,X7R,25V,G,SMD1206 | MURATA ELEC. NORTH AMERICA | GRM31CR71E106K | 8 |  | C1769,C1804,C1850,C1894,C1933,C1958,C1970,C2032 |  |  |  |  |  |  |
|  |  |  |  |  | 37 | 62011HS00-026-G |  | CAP,10uF,+/-10%,X7R,25V,G,SMD1206 | SAMSUNG SEMICONDUCTOR | CL31B106KAHNNNE |  |  |  |  |  |  |  |  |  |
|  |  |  |  |  | 37 | 62011HS00-023-G |  | CAP,10uF,+/-10%,X7R,25V,G,SMD1206 | TAIYO ELECTRIC IND.CO.LTD | TMK316B7106KL-TD |  |  |  |  |  |  |  |  |  |
|  |  |  |  | 38 | 38 | 620130V00-015-G |  | CAP,10uF,+/-20%,X6S,16V,G,SMD0603 | MURATA ELEC. NORTH AMERICA | GRM188C81C106MA73D | 8 |  | PBNC1,PANC8,PQPC16,C2013,C2015,C2017,C2019,PSRC3008 |  |  |  |  |  |  |
|  |  |  |  |  | 38 | 620130V00-023-G |  | CAP,10uF,+/-20%,X6S,16V,G,SMD0603 | TAIYO ELECTRIC IND.CO.LTD | EMK107BC6106MA-T |  |  |  |  |  |  |  |  |  |
|  |  |  |  |  | 38 | 620130V00-026-G |  | CAP,10uF,+/-20%,X6S,16V,G,SMD0603 | SAMSUNG | CL10X106MO8NRNC |  |  |  |  |  |  |  |  |  |
|  |  |  |  | 39 | 39 | 62010G800-015-G |  | CAP,22nF,+/-10%,X7R,16V,G,SMD0402 | MURATA ELEC. NORTH AMERICA | GRM155R71C223K | 3 |  | PHAC4,C2063,C2129 |  |  |  |  |  |  |
|  |  |  |  |  | 39 | 62010G800-026-G |  | CAP,22nF,+/-10%,X7R,16V,G,SMD0402 | SAMSUNG SEMICONDUCTOR | CL05B223KO5NNNC |  |  |  |  |  |  |  |  |  |
|  |  |  |  |  | 39 | 62010G800-023-G |  | CAP,22nF,+/-10%,X7R,16V,G,SMD0402 | TAIYO ELECTRIC IND.CO.LTD | EMK105B7223KV-F |  |  |  |  |  |  |  |  |  |
|  |  |  |  | 40 | 40 | 620110V00-015-G |  | CAP,1.2nF,+/-10%,X7R,50V,G,SMD0402 | MURATA ELEC. NORTH AMERICA | GRM155R71H122K | 1 |  | C2066 |  |  |  |  |  |  |
|  |  |  |  |  | 40 | 620110V00-026-G |  | CAP,1.2nF,+/-10%,X7R,50V,G,SMD0402 | SAMSUNG SEMICONDUCTOR | CL05B122KB5NNNC |  |  |  |  |  |  |  |  |  |
|  |  |  |  |  | 40 | 620110V00-023-G |  | CAP,1.2nF,+/-10%,X7R,50V,G,SMD0402 | TAIYO ELECTRIC IND.CO.LTD | UMK105B7122KV-F |  |  |  |  |  |  |  |  |  |
|  |  |  |  | 41 | 41 | 62012TW00-015-G |  | CAP,470nF,+/-10%,X7R,16V,G,SMD0402 | MURATA ELEC. NORTH AMERICA | GRM155R71C474KE01D | 2 |  | C2081,C2082 |  |  |  |  |  |  |
|  |  |  |  | 42 | 42 | 620131D00-015-G |  | CAP,1uF,+/-10%,X6S,16V,G,SMD0402 | MURATA ELEC. NORTH AMERICA | GRM155C81C105KE11J | 7 |  | PHAC1,PANC1,PBNC2,PHAC7,PALC37,PBLC62,C2111 |  |  |  |  |  |  |
|  |  |  |  |  | 42 | 620131D00-023-G |  | CAP,1uF,+/-10%,X6S,16V,G,SMD0402 | TAIYO ELECTRIC IND.CO.LTD | EMK105C6105KV-F |  |  |  |  |  |  |  |  |  |
|  |  |  |  | 43 | 43 | 620102S00-015-G |  | CAP,33pF,+/-5%,NPO(C0G),50V,G,SMD0402 | MURATA ELEC. NORTH AMERICA | GRM1555C1H330J | 9 |  | PUAC3,PSAC3,PRAC3,PQAC3,PPAC3,PIAC3,PFAC3,PEAC3,C2146 |  |  |  |  |  |  |
|  |  |  |  |  | 43 | 620102S00-023-G |  | CAP,33pF,+/-5%,NPO(C0G),50V,G,SMD0402 | TAIYO ELECTRIC IND.CO.LTD | UMK105CG330JV-F |  |  |  |  |  |  |  |  |  |
|  |  |  |  |  | 43 | 620102S00-026-G |  | CAP,33pF,+/-5%,NPO(C0G),50V,G,SMD0402 | SAMSUNG SEMICONDUCTOR | CL05C330JB5NNNC |  |  |  |  |  |  |  |  |  |
|  |  |  |  | 44 | 44 | 62012H100-015-G |  | CAP,10uF,+/-20%,X6S,10V,G,SMD0603 | MURATA ELEC. NORTH AMERICA | GRM188C81A106M | 11 |  | PSTC16,PFRC16,C2147,C2148,C2149,C2150,C2151,C182,C225,C273,C812 |  |  |  |  |  |  |
|  |  |  |  |  | 44 | 62012H100-026-G |  | CAP,10uF,+/-20%,X6S,10V,G,SMD0603 | SAMSUNG SEMICONDUCTOR | CL10X106MP8NRNC |  |  |  |  |  |  |  |  |  |
|  |  |  |  |  | 44 | 62012H100-023-G |  | CAP,10uF,+/-20%,X6S,10V,G,SMD0603 | TAIYO ELECTRIC IND.CO.LTD | LMK107BC6106MA-T |  |  |  |  |  |  |  |  |  |
|  |  |  |  | 45 | 45 | 62012PS00-015-G |  | CAP,10uF,+/-20%,X6S,4V,G,SMD0402 | MURATA ELEC. NORTH AMERICA | GRM155C80G106M | 495 |  | PBFC28,PBEC28,PAFC28,PAEC28,PBMC29,PBFC29,PBEC29,PBAC29,PAMC29,PAFC29,PAEC29,PAAC29,PBMC30,PBFC30,PBEC30,PBAC30,PAMC30,PAFC30,PAEC30,PAAC30,PBMC31,PBFC31,PBEC31,PBAC31,PAMC31,PAFC31,PAEC31,PAAC31,PBMC32,PBFC32,PBEC32,PBAC32,PAMC32,PAFC32,PAEC32,PAAC32,PBMC33,PBFC33,PBEC33,PBAC33,PAMC33,PAFC33,PAEC33,PAAC33,PBMC34,PBFC34,PBEC34,PBAC34,PAMC34,PAFC34,PAEC34,PAAC34,PBMC35,PBFC35,PBEC35,PBAC35,PAMC35,PAFC35,PAEC35,PAAC35,PBMC36,PBFC36,PBEC36,PBAC36,PAMC36,PAFC36,PAEC36,PAAC36,PBMC37,PBFC37,PBEC37,PBAC37,PAMC37,PAFC37,PAEC37,PAAC37,PBMC38,PBFC38,PBEC38,PBAC38,PAMC38,PAFC38,PAEC38,PAAC38,PBMC39,PBFC39,PBEC39,PBAC39,PAMC39,PAFC39,PAEC39,PAAC39,PBMC40,PBFC40,PBEC40,PBAC40,PAMC40,PAFC40,PAEC40,PAAC40,PBMC41,PBFC41,PBEC41,PBAC41,PAMC41,PAFC41,PAEC41,PAAC41,PBMC42,PBFC42,PBEC42,PBAC42,PAMC42,PAFC42,PAEC42,PAAC42,PBMC43,PBFC43,PBEC43,PBAC43,PAMC43,PAFC43,PAEC43,PAAC43,PBMC44,PBFC44,PBEC44,PBAC44,PAMC44,PAFC44,PAEC44,PAAC44,PBMC45,PBFC45,PBEC45,PBAC45,PAMC45,PAFC45,PAEC45,PAAC45,PBMC46,PBFC46,PBEC46,PBAC46,PAMC46,PAFC46,PAEC46,PAAC46,PBMC47,PBFC47,PBEC47,PBAC47,PAMC47,PAFC47,PAEC47,PAAC47,PBMC48,PBFC48,PBEC48,PBAC48,PAMC48,PAFC48,PAEC48,PAAC48,PBMC49,PBFC49,PBEC49,PBAC49,PAMC49,PAFC49,PAEC49,PAAC49,PBMC50,PBFC50,PBEC50,PBAC50,PAMC50,PAFC50,PAEC50,PAAC50,PBMC51,PBFC51,PBEC51,PBAC51,PAMC51,PAFC51,PAEC51,PAAC51,PBMC52,PBFC52,PBEC52,PBAC52,PAMC52,PAFC52,PAEC52,PAAC52,PBMC53,PBFC53,PBEC53,PBAC53,PAMC53,PAFC53,PAEC53,PAAC53,PBMC54,PBFC54,PBEC54,PBAC54,PAMC54,PAFC54,PAEC54,PAAC54,PBMC55,PBFC55,PBEC55,PBAC55,PAMC55,PAFC55,PAEC55,PAAC55,PBMC56,PBFC56,PBEC56,PBAC56,PAMC56,PAFC56,PAEC56,PAAC56,PBMC57,PBFC57,PBEC57,PBAC57,PAMC57,PAFC57,PAEC57,PAAC57,PBMC58,PBAC58,PAMC58,PAAC58,PBAC59,PAAC59,PBAC60,PAAC60,PBAC61,PAAC61,PBFC62,PBEC62,PBAC62,PAFC62,PAEC62,PAAC62,PBMC63,PBFC63,PBEC63,PBAC63,PAMC63,PAFC63,PAEC63,PAAC63,PBMC64,PBFC64,PBEC64,PBAC64,PAMC64,PAFC64,PAEC64,PAAC64,PBMC65,PBFC65,PBEC65,PBAC65,PAMC65,PAFC65,PAEC65,PAAC65,PBMC66,PBFC66,PBEC66,PBAC66,PAMC66,PAFC66,PAEC66,PAAC66,PBMC67,PBFC67,PBEC67,PBAC67,PAMC67,PAFC67,PAEC67,PAAC67,PBMC68,PBFC68,PBEC68,PBAC68,PAMC68,PAFC68,PAEC68,PAAC68,PBMC69,PBFC69,PBEC69,PBAC69,PAMC69,PAFC69,PAEC69,PAAC69,PBMC70,PBFC70,PBEC70,PBAC70,PAMC70,PAFC70,PAEC70,PAAC70,PBMC71,PBFC71,PBEC71,PBAC71,PAMC71,PAFC71,PAEC71,PAAC71,PBMC72,PBAC72,PAMC72,PAAC72,PBAC73,PAAC73,PBAC74,PAAC74,PBAC75,PAAC75,PBAC76,PAAC76,PBAC77,PAAC77,PBAC78,PAAC78,PBAC81,PAAC81,PBAC82,PAAC82,PBAC83,PAAC83,PBAC84,PAAC84,PBAC85,PAAC85,PBAC86,PAAC86,PBAC87,PAAC87,PBAC88,PAAC88,PBAC89,PAAC89,PBAC90,PAAC90,PBAC91,PAAC91,PBAC92,PAAC92,PBAC93,PAAC93,PBAC94,PAAC94,PBAC95,PAAC95,PBAC96,PAAC96,PBAC97,PAAC97,PBAC98,PAAC98,PBAC99,PAAC99,PBAC100,PAAC100,PBAC101,PAAC101,PBAC102,PAAC102,PBAC103,PAAC103,PBAC104,PAAC104,PBAC105,PAAC105,PBAC106,PAAC106,PBAC107,PAAC107,PBAC108,PAAC108,PBAC109,PAAC109,PBAC110,PAAC110,PBAC113,PAAC113,PBAC114,PAAC114,PBAC115,PAAC115,PBAC116,PAAC116,PBAC117,PAAC117,PBAC118,PAAC118,PBAC119,PAAC119,PBAC120,PAAC120,PBAC121,PAAC121,PBAC122,PAAC122,PBAC127,PAAC127,PBAC128,PAAC128,PBAC129,PAAC129,PBAC130,PAAC130,PBAC131,PAAC131,PBAC132,PAAC132,PBAC133,PAAC133,PBAC134,PAAC134,PBAC135,PAAC135,PBAC136,PAAC136,PBAC137,PAAC137,PBAC138,PAAC138,PBAC139,PAAC139,PBAC140,PAAC140,PBAC141,PAAC141,PBAC142,PAAC142,PBAC143,PAAC143,PBAC144,PAAC144,PBAC145,PAAC145,PBAC146,PAAC146,PBAC147,PAAC147,PBAC148,PAAC148,PBAC149,PAAC149,PBAC150,PAAC150,PBAC151,PAAC151,PBAC152,PAAC152,PBAC153,PAAC153,PBAC154,PAAC154,PBAC155,PAAC155,PBAC156,PAAC156,PBFC501,PBEC501,PAFC501,PAEC501,C2168,C2169,C2170,C2172,C2173,C2174,C2175,C2176,C2177,C2178,C2179 |  |  |  |  |  |  |
|  |  |  |  |  | 45 | 62012PS00-023-G |  | CAP,10uF,+/-20%,X6S,4V,G,SMD0402 | TAIYO ELECTRIC IND.CO.LTD | AMK105CC6106MV-F |  |  |  |  |  |  |  |  |  |
|  |  |  |  |  | 45 | 62012PS00-026-G |  | CAP,10uF,+/-20%,X6S,4V,G,SMD0402 | SAMSUNG | CL05X106MR5NUNC |  |  |  |  |  |  |  |  |  |
|  |  |  |  | 46 | 46 | 620108B00-015-G |  | CAP,120pF,+/-5%,NPO(C0G),50V,G,SMD0402 | MURATA ELEC. NORTH AMERICA | GRM1555C1H121J | 4 |  | C2182,C2183,C2184,C2185 |  |  |  |  |  |  |
|  |  |  |  |  | 46 | 620108B00-023-G |  | CAP,120pF,+/-5%,NPO(C0G),50V,G,SMD0402 | TAIYO | UMK105CG121JV-F |  |  |  |  |  |  |  |  |  |
|  |  |  |  |  | 46 | 620108B00-026-G |  | CAP,120pF,+/-5%,NPO(C0G),50V,G,SMD0402 | SAMSUNG | CL05C121JB5NNNC |  |  |  |  |  |  |  |  |  |
|  |  |  |  | 47 | 47 | 521803M00-227-G |  | Diode,Array-TVS,UCLAMP0508T.TCT,Level 4,5V,G,SLP,SMD-9 | SEMTECH CORPORATION. | UCLAMP0508T.TCT | 1 |  | DN1 |  |  |  |  |  |  |
|  |  |  |  | 48 | 48 | 520300A00-237-G |  | DIODE,Schottky,SD103AW-7-F,40V,0.35A,G,SOD123-2,SMD | DIODES INCORPORATION | SD103AW-7-F | 1 |  | D19 |  |  |  |  |  |  |
|  |  |  |  | 49 | 49 | 520100200-237-G |  | DIODE,Switching,1N4148W-7-F,100V,0.15A,G,SOD123-2,SMD | DIODES INCORPORATION | 1N4148W-7-F | 7 |  | PHAD6,D20,D21,D29,D30,D31,D32 |  |  |  |  |  |  |
|  |  |  |  | 50 | 50 | 520308A00-237-G |  | Diode,Schottky,B0530WS-7-F,30V,500mA,G,SOD-323-2,SMD | DIODES INCORPORATION | B0530WS-7-F | 6 |  | D22,D23,D24,D25,D26,D27 |  |  |  |  |  |  |
|  |  |  |  | 51 | 51 | 52010MP00-237-G |  | Diode,Rectifier,ES2D-13-F,200V,2A,G,SMB-2,SMD | DIODES INCORPORATION | ES2D-13-F | 3 |  | D28,D35,D36 |  |  |  |  |  |  |
|  |  |  |  | 52 | 52 | 520308D00-237-G |  | DIODE,Schottky Rectifier,1N5819HW-7-F,40V,1A,G,SOD123-2,SMD | DIODES INCORPORATION | 1N5819HW-7-F | 1 |  | D33 |  |  |  |  |  |  |
|  |  |  |  | 53 | 53 | 520401Y00-237-G |  | DIODE,Zener,BZT52C3V6-7-F,3.6V,5mA,G,SOD123-2,SMD | DIODES INCORPORATION | BZT52C3V6-7-F | 1 |  | D34 |  |  |  |  |  |  |
|  |  |  |  | 54 | 54 | 520304B00-237-G |  | DIODE,Schottky,BAT54WS-7-F,30V,0.1A,G,SOD323-2,SMD | DIODES INCORPORATION | BAT54WS-7-F | 4 |  | D53,D54,D55,D56 |  |  |  |  |  |  |
|  |  |  |  | 55 | 55 | 52030NP00-185-G |  | DIODE,Schottky,RB521S30,30V,200mA,G,SOD523-2,SMD | FAIRCHILD SEMICONDUCTOR CORP | RB521S30 | 1 |  | D57 |  |  |  |  |  |  |
|  |  |  |  | 56 | 56 | 521800900-227-G |  | DIODE,Array-TVS,SRV05-4.TCT,5V,12A,G,SOT23-6,SMD | SEMTECH CORPORATION. | SRV05-4.TCT | 3 |  | ED1,ED2,ED3 |  |  |  |  |  |  |
|  |  |  |  | 57 | 57 | 720101900-015-G |  | FB,60 Ohm@100MHz,+/-25%,3A,25mOhm,G,SMD0805 | MURATA ELEC. NORTH AMERICA | BLM21PG600SN1D | 1 |  | FB1 |  |  |  |  |  |  |
|  |  |  |  | 58 | 58 | 720406E00-015-G |  | Common Choke,90Ohm@100MHz,+/-25%,220mA,G,SMD0805 | MURATA ELEC. NORTH AMERICA | DLW21HN900HQ2L | 3 |  | FL1,FL4,FL10 |  |  |  |  |  |  |
|  |  |  |  | 59 | 59 | 720400201-015-G |  | Filter,Common Mode,90Ohm@100MHz,+/-25%,330mA,G,SMD0805 | MURATA ELEC. NORTH AMERICA | DLW21HN900SQ2L | 7 |  | FL2,FL3,FL5,FL6,FL7,FL8,FL9 |  |  |  |  |  |  |
|  |  |  |  | 60 | 60 | 730100400-086-G |  | Fuse,Very fast acting,3A,32V,G,SMD0603 | LITTELFUSE FAR EAST PTE LTD | 0467003.NR | 2 |  | FS2,FS3 |  |  |  |  |  |  |
|  |  |  |  | 61 | 61 | 730102701-086-G |  | Fuse,Fast acting,32V,7A,G,SMD1206 | LITTELFUSE FAR EAST PTE LTD | 0440007.WR | 6 |  | FS4,FS9,FS12,FS15,FS16,FS21 |  |  |  |  |  |  |
|  |  |  |  | 62 | 62 | 730103M00-086-G |  | Fuse,Fast acting,32V,5A,G,SMD0603 | LITTELFUSE FAR EAST PTE LTD | 0438005.WR | 11 |  | FS5,FS8,FS11,FS14,FS17,FS19,FS20,FS23,FS24,FS25,FS26 |  |  |  |  |  |  |
|  |  |  |  | 63 | 63 | 730102B01-086-G |  | Fuse,Fast acting,32V,1A,G,SMD0603 | LITTELFUSE FAR EAST PTE LTD | 0438001.WR | 5 |  | FS6,FS7,FS10,FS13,FS18 |  |  |  |  |  |  |
|  |  |  |  | 64 | 64 | 730102000-086-G |  | Fuse,Fast acting,24V,10A,G,SMD1206 | LITTELFUSE FAR EAST PTE LTD | 0501010.WR | 1 |  | FS22 |  |  |  |  |  |  |
|  |  |  |  | 65 | 65 | 730108F00-086-G |  | Fuse,Fast acting,500V,30A,G,SMD | LITTELFUSE FAR EAST PTE LTD | 0505030.MXP | 3 |  | FS27,FS28,FS30 |  |  |  |  |  |  |
|  |  |  |  | 66 | 66 | 730106S00-088-G |  | Fuse,Fast acting,125V,15A,G,SMD2010 | COOPER BUSSMANN, INC. | CB61F15A-TR2 | 1 |  | FS29 |  |  |  |  |  |  |
|  |  |  |  | 67 | 67 | 340718900-245-G |  | CONN,SAS,V/T,0.6mm,30u,G,SMD-74 | AMPHENOL SHANGHAI CORP. | U10-B074-260T | 4 |  | J28,J30,J31,J33 |  |  |  |  |  |  |
|  |  |  |  | 68 | 68 | 61010KR00-017-G |  | RES,4.99 Ohm,+/-1%,1/10W,G,SMD0603 | KOA SPEER ELECTRONICS, INC. | RK73H1JTTD4R99F | 1 |  | R1756 |  |  |  |  |  |  |
|  |  |  |  | 69 | 69 | 52112H800-289-G |  | LED,Blu,LTST-C193TBKT-LO,5V,20mA,G,SMD | LITE-ON TECHNOLOGY CORPORATION | LTST-C193TBKT-LO | 1 |  | LED1 |  |  |  |  |  |  |
|  |  |  |  | 70 | 70 | 52111AE00-289-G |  | LED,Ora,LTST-C281KFKT-5A,5V,30mA,G,SMD0402 | LITE-ON TECHNOLOGY CORPORATION | LTST-C281KFKT-5A | 3 |  | LED2,LED4,LED6 |  |  |  |  |  |  |
|  |  |  |  | 71 | 71 | 52111J100-289-G |  | LED,Gre,LTST-C281KGKT-5A,2.3V,30mA,G,SMD0402 | LITE-ON TECHNOLOGY CORPORATION | LTST-C281KGKT-5A | 3 |  | LED3,LED5,LED7 |  |  |  |  |  |  |
|  |  |  |  | 72 | 72 | 52113AY00-289-G |  | LED,Red,LTL-42NEW8DH184P,5V,20mA,G,DIP-2 | LITE-ON TECHNOLOGY CORPORATION | LTL-42NEW8DH184P | 2 |  | LED8,LED9 |  |  |  |  |  |  |
|  |  |  |  | 73 | 73 | 52113B000-289-G |  | LED,Yellow,LTL-42NSV8DH184P,5V,20mA,G,DIP-2 | LITE-ON TECHNOLOGY CORPORATION | LTL-42NSV8DH184P | 2 |  | LED10,LED14 |  |  |  |  |  |  |
|  |  |  |  | 74 | 74 | 52113AW00-289-G |  | LED,Green,LTL-42NGY8DH184P,5V,20mA,G,DIP-2 | LITE-ON TECHNOLOGY CORPORATION | LTL-42NGY8DH184P | 2 |  | LED11,LED12 |  |  |  |  |  |  |
|  |  |  |  | 75 | 75 | 52113B100-289-G |  | LED,Blue,LTL42TB6NH184P,5V,30mA,G,DIP-2 | LITE-ON TECHNOLOGY CORPORATION | LTL42TB6NH184P | 1 |  | LED13 |  |  |  |  |  |  |
|  |  |  |  | 76 | 76 | 52110FE00-289-G |  | LED,Red,LTST-C190KRKT,2.4V,30mA,G,SMD0603 | LITE-ON TECHNOLOGY CORPORATION | LTST-C190KRKT | 3 |  | LED63,LED64,LED65 |  |  |  |  |  |  |
|  |  |  |  | 77 | 77 | 52110LN00-289-G |  | LED,Gre,LTST-C191KGKT,2.4V,30mA,G,SMD0603 | LITE-ON TECHNOLOGY CORPORATION | LTST-C191KGKT | 37 |  | LED66,LED67,LED68,LED69,LED70,LED71,LED72,LED73,LED74,LED75,LED76,LED77,LED78,LED79,LED80,LED81,LED82,LED83,LED84,LED85,LED86,LED87,LED88,LED89,LED90,LED91,LED92,LED93,LED94,LED95,LED96,LED97,LED98,LED99,LED100,LED101,LED102 |  |  |  |  |  |  |
|  |  |  |  | 78 | 78 | 21040HY00-283-G |  | IC,BROADCOM,BCM5719A1KFBG,A1,G,FBGA-256,SMD | BROADCOM SINGAPORE PTE LTD. | BCM5719A1KFBG | 1 |  | LOM1 |  |  |  |  |  |  |
|  |  |  |  | 79 | 79 | 720108301-015-G |  | FB,600 Ohm@100MHz,+/-25%,500mA,350mOhm,G,SMD0603 | MURATA ELEC. NORTH AMERICA | BLM18EG601SN1D | 14 |  | L2,L3,L4,L5,L6,L8,L9,L10,L11,L12,L13,L14,L15,L16 |  |  |  |  |  |  |
|  |  |  |  | 80 | 80 | 630332000-053-G |  | IND,3.3uH@100KHz,+/-20%,2.57A,26mOhm,SHLD,G,SMD | TOKO INC. | #A916CY-3R3M=P3 | 1 |  | L7 |  |  |  |  |  |  |
|  |  |  |  | 81 | 81 | 720106E00-015-G |  | FB,330 Ohm@100MHz,+/-25%,500mA,300mOhm,G,SMD0603 | MURATA ELEC. NORTH AMERICA | BLM18EG331TN1D | 1 |  | L17 |  |  |  |  |  |  |
|  |  |  |  | 82 | 82 | 720105P00-016-G |  | FB,80 Ohm@100MHz,+/-25%,500mA,150mOhm,G,SMD0603 | TDK ELECTRONICS EUROPE GMBH | MMZ1608S800AT | 4 |  | L22,L23,L24,L25 |  |  |  |  |  |  |
|  |  |  |  | 83 | 83 | 72010CB00-015-G |  | FB,22 Ohm@100MHz,+/-25%,6A,10mOhm,G,SMD0805 | MURATA ELEC. NORTH AMERICA | BLM21PG220SN1D | 3 |  | L26,L28,L47 |  |  |  |  |  |  |
|  |  |  |  | 84 | 84 | 72010A400-023-G |  | FB,80Ohm@100MHz,+/-25%,4A,10mOhm,G,SMD1206 | TAIYO ELECTRIC IND.CO.LTD | FBMJ3216HS800-T | 2 |  | L34,L36 |  |  |  |  |  |  |
|  |  |  |  | 85 | 85 | 72010MK00-015-G |  | FB,80 Ohm@100MHz,+/-25%,1.5A,70mOhm,G,SMD0402 | MURATA ELEC. NORTH AMERICA | BLM15PD800SN1D | 7 |  | L35,L37,L38,L39,L40,L41,L42 |  |  |  |  |  |  |
|  |  |  |  | 86 | 86 | 720101M00-015-G |  | FB,600 Ohm@100MHz,+/-25%,200mA,650mOhm,G,SMD0603 | MURATA ELEC. NORTH AMERICA | BLM18BD601SN1D | 1 |  | L45 |  |  |  |  |  |  |
|  |  |  |  | 87 | 87 | 62111CS00-024-G |  | ECAP,68uF,+/-20%,100V,105C,G,SMD12.5*13.5,ESR<=320mOhm | PANASONIC INDUSTRIAL CO.,LTD. | EEVFK2A680Q | 6 |  | PSUCE1,PBACE1,PAACE1,PSUCE2,PBACE2,PAACE2 |  |  |  |  |  |  |
|  |  |  |  | 88 | 88 | 62111QQ00-019-G |  | ECAP,82uF,+/-20%,100V,105C,G,SMD12.5*13.5,ESR<=280mOhm | NICHICON CORPORATION | UCZ2A820MNQ1MS | 8 |  | PBMCE1,PAMCE1,PBFCE2,PBECE2,PAFCE2,PAECE2,PBACE3,PAACE3 |  |  |  |  |  |  |
|  |  |  |  | 89 | 89 | 62120ER01-024-G |  | ECAP,SPEA,470uF,+/-20%,2.5V,105C,G,SMD2816,ESR<=3mOhm | PANASONIC INDUSTRIAL CO.,LTD. | EEFGX0E471R | 50 |  | PBNCE1,PANCE1,PBNCE2,PANCE2,PBECE3,PALCE3,PAFCE3,PAECE3,PBMCE4,PBFCE4,PBECE4,PBACE4,PAMCE4,PALCE4,PAFCE4,PAECE4,PAACE4,PBMCE5,PBFCE5,PBECE5,PBACE5,PAMCE5,PAFCE5,PAECE5,PAACE5,PBMCE6,PBFCE6,PBECE6,PBACE6,PAMCE6,PAFCE6,PAECE6,PAACE6,PBMCE7,PBLCE7,PBFCE7,PBACE7,PAMCE7,PAACE7,PBLCE8,PBACE8,PAACE8,PBACE9,PAACE9,PBACE10,PAACE10,PBACE11,PAACE11,PBACE12,PAACE12 |  |  |  |  |  |  |
|  |  |  |  | 90 | 90 | 62012RJ00-015-G |  | CAP,4.7uF,+/-10%,X6S,16V,G,SMD0603 | MURATA ELEC. NORTH AMERICA | GRM188C81C475K | 34 |  | PBMC1,PBFC1,PBEC1,PBAC1,PAMC1,PAFC1,PAEC1,PAAC1,PBMC2,PBFC2,PBEC2,PBAC2,PAMC2,PAFC2,PAEC2,PAAC2,PBMC22,PBFC22,PBEC22,PBAC22,PAMC22,PAFC22,PAEC22,PAAC22,PBMC450,PBFC450,PBEC450,PBAC450,PAMC450,PAFC450,PAEC450,PAAC450,PBAC452,PAAC452 |  |  |  |  |  |  |
|  |  |  |  |  | 90 | 62012RJ00-023-G |  | CAP,4.7uF,+/-10%,X6S,16V,G,SMD0603 | TAIYO ELECTRIC IND.CO.LTD | EMK107BC6475KA-T |  |  |  |  |  |  |  |  |  |
|  |  |  |  |  | 90 | 62012RJ02-026-G |  | CAP,4.7uF,+/-10%,X6S,16V,G,SMD0603 | SAMSUNG | CL10X475KO8NRNC |  |  |  |  |  |  |  |  |  |
|  |  |  |  | 91 | 91 | 62010FF00-015-G |  | CAP,47pF,+/-5%,NPO(C0G),50V,G,SMD0402 | MURATA ELEC. NORTH AMERICA | GRM1555C1H470J | 12 |  | PBMC4,PBFC4,PBEC4,PBAC4,PAMC4,PAFC4,PAEC4,PAAC4,PSPC11,PIPC11,PFPC11,PEPC11 |  |  |  |  |  |  |
|  |  |  |  |  | 91 | 62010FF00-026-G |  | CAP,47pF,+/-5%,NPO(C0G),50V,G,SMD0402 | SAMSUNG SEMICONDUCTOR | CL05C470JB5NNNC |  |  |  |  |  |  |  |  |  |
|  |  |  |  |  | 91 | 62010FF00-023-G |  | CAP,47pF,+/-5%,NPO(C0G),50V,G,SMD0402 | TAIYO ELECTRIC IND.CO.LTD | UMK105CG470JV-F |  |  |  |  |  |  |  |  |  |
|  |  |  |  | 92 | 92 | 62010L800-015-G |  | CAP,1nF,+/-5%,NPO(C0G),50V,G,SMD0402 | MURATA ELEC. NORTH AMERICA | GRM1555C1H102J | 18 |  | PSPC5,PIPC5,PFPC5,PEPC5,PBMC5,PBAC5,PAMC5,PAAC5,PBAC23,PAAC23,PBMC95,PAMC95,PBAC125,PAAC125,PBFC451,PBEC451,PAFC451,PAEC451 |  |  |  |  |  |  |
|  |  |  |  |  | 92 | 62010L800-026-G |  | CAP,1nF,+/-5%,NPO(C0G),50V,G,SMD0402 | SAMSUNG SEMICONDUCTOR | CL05C102JB5NNNC |  |  |  |  |  |  |  |  |  |
|  |  |  |  | 93 | 93 | 62011DQ00-015-G |  | CAP,27nF,+/-10%,X7R,25V,G,SMD0402 | MURATA ELEC. NORTH AMERICA | GRM155R71E273KA88D | 8 |  | PBMC6,PBFC6,PBEC6,PBAC6,PAMC6,PAFC6,PAEC6,PAAC6 |  |  |  |  |  |  |
|  |  |  |  | 94 | 94 | 62010VD00-015-G |  | CAP,100nF,+/-10%,X7R,100V,G,SMD0603 | MURATA ELEC. NORTH AMERICA | GRM188R72A104K | 9 |  | PBEC11,PAFC11,PAEC11,PBMC12,PBFC12,PBAC12,PAMC12,PAAC12,PHAC14 |  |  |  |  |  |  |
|  |  |  |  |  | 94 | 62010VD00-026-G |  | CAP,100nF,+/-10%,X7R,100V,G,SMD0603 | SAMSUNG SEMICONDUCTOR | CL10B104KC8NNNC |  |  |  |  |  |  |  |  |  |
|  |  |  |  | 95 | 95 | 62011J601-015-G |  | CAP,2.2uF,+/-10%,X7R,100V,G,SMD1210 | MURATA ELEC. NORTH AMERICA | GRM32ER72A225K | 42 |  | PSUC1,PSUC2,PBMC13,PBFC13,PBEC13,PBAC13,PAMC13,PAFC13,PAEC13,PAAC13,PBMC14,PBFC14,PBEC14,PBAC14,PAMC14,PAFC14,PAEC14,PAAC14,PBMC15,PBFC15,PBEC15,PBAC15,PAMC15,PAFC15,PAEC15,PAAC15,PBAC16,PAAC16,PBEC17,PBAC17,PAAC17,PBAC18,PAAC18,PBAC19,PAAC19,PAFC20,PAAC20,PBMC21,PBFC21,PBAC21,PAMC21,PAEC21 |  |  |  |  |  |  |
|  |  |  |  |  | 95 | 62011J600-026-G |  | CAP,2.2uF,+/-10%,X7R,100V,G,SMD1210 | SAMSUNG SEMICONDUCTOR | CL32B225KCJSNNE |  |  |  |  |  |  |  |  |  |
|  |  |  |  | 96 | 96 | 620107L00-015-G |  | CAP,2.2nF,+/-10%,X7R,50V,G,SMD0402 | MURATA ELEC. NORTH AMERICA | GRM155R71H222K | 16 |  | PSRC2,PSPC12,PIPC12,PFPC12,PEPC12,PSIC18,PETC18,PERC18,PBFC25,PBEC25,PAFC25,PBMC26,PBAC26,PAMC26,PAAC26,PAEC516 |  |  |  |  |  |  |
|  |  |  |  |  | 96 | 620107L00-026-G |  | CAP,2.2nF,+/-10%,X7R,50V,G,SMD0402 | SAMSUNG SEMICONDUCTOR | CL05B222KB5NNNC |  |  |  |  |  |  |  |  |  |
|  |  |  |  |  | 96 | 620107L03-023-G |  | CAP,2.2nF,+/-10%,X7R,50V,G,SMD0402 | TAIYO ELECTRIC IND.CO.LTD | UMK105B7222KV-F |  |  |  |  |  |  |  |  |  |
|  |  |  |  | 97 | 97 | 62011DA02-015-G |  | CAP,1uF,+/-10%,X7R,100V,G,SMD1206 | MURATA ELEC. NORTH AMERICA | GRM31CR72A105KA01K | 6 |  | PBMC27,PBAC27,PAMC27,PAAC27,PBAC111,PAAC111 |  |  |  |  |  |  |
|  |  |  |  |  | 97 | 62011DA00-015-G |  | CAP,1uF,+/-10%,X7R,100V,G,SMD1206 | MURATA ELEC. NORTH AMERICA | GRM31CR72A105K |  |  |  |  |  |  |  |  |  |
|  |  |  |  |  | 97 | 62011DA00-023-G |  | CAP,1uF,+/-10%,X7R,100V,G,SMD1206 | TAIYO ELECTRIC IND.CO.LTD | HMK316B7105KL-T |  |  |  |  |  |  |  |  |  |
|  |  |  |  |  | 97 | 62011DA00-026-G |  | CAP,1uF,+/-10%,X7R,100V,G,SMD1206 | SAMSUNG SEMICONDUCTOR | CL31B105KCHNNNE |  |  |  |  |  |  |  |  |  |
|  |  |  |  | 98 | 98 | 62010WW01-015-G |  | CAP,1.8nF,+/-10%,X7R,50V,G,SMD0402 | MURATA ELEC. NORTH AMERICA | GRM155R71H182KA01D | 8 |  | PBFC59,PBEC59,PAFC59,PAEC59,PBMC60,PAMC60,PBAC124,PAAC124 |  |  |  |  |  |  |
|  |  |  |  |  | 98 | 62010WW00-026-G |  | CAP,1.8nF,+/-10%,X7R,50V,G,SMD0402 | SAMSUNG | CL05B182KB5NNNC |  |  |  |  |  |  |  |  |  |
|  |  |  |  | 99 | 99 | 620127602-015-G |  | CAP,47uF,+/-20%,X6S,4V,G,SMD0805 | MURATA ELEC. NORTH AMERICA | GRM21BC80G476M | 636 |  | PBNC18,PANC18,PBNC19,PANC19,PBNC20,PANC20,PBNC21,PANC21,PBNC22,PANC22,PBNC23,PANC23,PALC25,PALC26,PALC27,PALC28,PALC29,PALC30,PALC31,PALC32,PALC33,PALC34,PBLC45,PBLC46,PBLC47,PBLC48,PBLC49,PBLC50,PBLC51,PBLC52,PBLC53,PBLC63,PBMC73,PAMC73,PBMC74,PAMC74,PBMC75,PAMC75,PBMC76,PAMC76,PBMC77,PAMC77,PBMC78,PAMC78,PBMC79,PAMC79,PBMC80,PAMC80,PBMC81,PAMC81,PBMC82,PAMC82,PBMC83,PAMC83,PBMC84,PAMC84,PBMC85,PAMC85,PBMC86,PAMC86,PBMC87,PAMC87,PBMC88,PAMC88,PBMC89,PAMC89,PBMC90,PAMC90,PBMC91,PAMC91,PBMC92,PAMC92,PBMC93,PAMC93,PBMC94,PAMC94,PBMC96,PAMC96,PBMC97,PAMC97,PBMC98,PAMC98,PBMC99,PAMC99,PBMC100,PAMC100,PBMC101,PAMC101,PBMC102,PAMC102,PBMC103,PAMC103,PBAC167,PAAC167,PBAC168,PAAC168,PBAC169,PAAC169,PBAC170,PAAC170,PBAC171,PAAC171,PBAC172,PAAC172,PBAC173,PAAC173,PBAC174,PAAC174,PBAC175,PAAC175,PBAC176,PAAC176,PBAC177,PAAC177,PBAC178,PAAC178,PBAC179,PAAC179,PBAC180,PAAC180,PBAC181,PAAC181,PBAC182,PAAC182,PBAC183,PAAC183,PBAC184,PAAC184,PBAC185,PAAC185,PBAC186,PAAC186,PBAC187,PAAC187,PBAC188,PAAC188,PBAC189,PAAC189,PBAC190,PAAC190,PBAC191,PAAC191,PBAC192,PAAC192,PBAC193,PAAC193,PBAC194,PAAC194,PBAC195,PAAC195,PBAC196,PAAC196,PBAC197,PAAC197,PBAC198,PAAC198,PBAC199,PAAC199,PBAC200,PAAC200,PBAC201,PAAC201,PBAC202,PAAC202,PBAC203,PAAC203,PBAC204,PAAC204,PBAC205,PAAC205,PBAC206,PAAC206,PBAC207,PAAC207,PBAC208,PAAC208,PBAC209,PAAC209,PBAC210,PAAC210,PBAC211,PAAC211,PBAC212,PAAC212,PBAC213,PAAC213,PBAC214,PAAC214,PBAC215,PAAC215,PBAC216,PAAC216,PBAC217,PAAC217,PBAC218,PAAC218,PBAC219,PAAC219,PBAC220,PAAC220,PBAC221,PAAC221,PBAC222,PAAC222,PBAC223,PAAC223,PBAC224,PAAC224,PBAC225,PAAC225,PBAC226,PAAC226,PBAC227,PAAC227,PBAC228,PAAC228,PBAC229,PAAC229,PBAC230,PAAC230,PBAC231,PAAC231,PBAC232,PAAC232,PBAC233,PAAC233,PBAC234,PAAC234,PBAC235,PAAC235,PBAC236,PAAC236,PBAC237,PAAC237,PBAC238,PAAC238,PBAC239,PAAC239,PBAC240,PAAC240,PBAC241,PAAC241,PBAC242,PAAC242,PBAC243,PAAC243,PBAC244,PAAC244,PBAC245,PAAC245,PBAC246,PAAC246,PBFC300,PBEC300,PAFC300,PAEC300,PBFC301,PBEC301,PAFC301,PAEC301,PBFC302,PBEC302,PAFC302,PAEC302,PBFC303,PBEC303,PAFC303,PAEC303,PBFC304,PBEC304,PAFC304,PAEC304,PBFC305,PBEC305,PAFC305,PAEC305,PBFC306,PBEC306,PAFC306,PAEC306,PBFC307,PBEC307,PAFC307,PAEC307,PBFC308,PBEC308,PAFC308,PAEC308,PBFC309,PBEC309,PAFC309,PAEC309,PBFC310,PBEC310,PAFC310,PAEC310,PBFC311,PBEC311,PAFC311,PAEC311,PBFC312,PBEC312,PAFC312,PAEC312,PBFC313,PBEC313,PAFC313,PAEC313,PBFC314,PBEC314,PAFC314,PAEC314,PBFC315,PBEC315,PAFC315,PAEC315,PBFC316,PBEC316,PAFC316,PAEC316,PBFC317,PBEC317,PAFC317,PAEC317,PBFC318,PBEC318,PAFC318,PAEC318,PBFC319,PBEC319,PAFC319,PAEC319,PBFC320,PBEC320,PAFC320,PAEC320,PBFC321,PBEC321,PAFC321,PAEC321,PBFC322,PBEC322,PAFC322,PAEC322,PBFC323,PBEC323,PAFC323,PAEC323,PBFC324,PBEC324,PAFC324,PAEC324,PBFC325,PBEC325,PAFC325,PAEC325,PBFC326,PBEC326,PAFC326,PAEC326,PBFC327,PBEC327,PAFC327,PAEC327,PBFC328,PBEC328,PAFC328,PAEC328,PBFC329,PBEC329,PAFC329,PAEC329,PBFC330,PBEC330,PAFC330,PAEC330,PBFC331,PBEC331,PAFC331,PAEC331,PBFC332,PBEC332,PAFC332,PAEC332,PBFC333,PBEC333,PAFC333,PAEC333,PBFC334,PBEC334,PAFC334,PAEC334,PBFC335,PBEC335,PAFC335,PAEC335,PBFC336,PBEC336,PAFC336,PAEC336,PBFC337,PBEC337,PAFC337,PAEC337,PBFC338,PBEC338,PAFC338,PAEC338,PBFC339,PBEC339,PAFC339,PAEC339,PBFC340,PBEC340,PAFC340,PAEC340,PBFC341,PBEC341,PAFC341,PAEC341,PBFC342,PBEC342,PAFC342,PAEC342,PBFC343,PBEC343,PAFC343,PAEC343,PBFC344,PBEC344,PAFC344,PAEC344,PBFC345,PBEC345,PAFC345,PAEC345,PBFC346,PBEC346,PAFC346,PAEC346,PBFC347,PBEC347,PAFC347,PAEC347,PBFC348,PBEC348,PAFC348,PAEC348,PBFC349,PBEC349,PAFC349,PAEC349,PBFC350,PBEC350,PAFC350,PAEC350,PBFC351,PBEC351,PAFC351,PAEC351,PBFC352,PBEC352,PAFC352,PAEC352,PBFC353,PBEC353,PAFC353,PAEC353,PBFC354,PBEC354,PAFC354,PAEC354,PBFC355,PBEC355,PAFC355,PAEC355,PBFC356,PBEC356,PAFC356,PAEC356,PBFC357,PBEC357,PAFC357,PAEC357,PBFC358,PBEC358,PAFC358,PAEC358,PBFC359,PBEC359,PAFC359,PAEC359,PBFC360,PBEC360,PAFC360,PAEC360,PBFC361,PBEC361,PAFC361,PAEC361,PBFC362,PBEC362,PAFC362,PAEC362,PBFC363,PBEC363,PAFC363,PAEC363,PBFC364,PBEC364,PAFC364,PAEC364,PBFC365,PBEC365,PAFC365,PAEC365,PBFC366,PBEC366,PAFC366,PAEC366,PBFC367,PBEC367,PAFC367,PAEC367,PBFC368,PBEC368,PAFC368,PAEC368,PBFC369,PBEC369,PAFC369,PAEC369,PBFC370,PBEC370,PAFC370,PAEC370,PBFC371,PBEC371,PAFC371,PAEC371,PBFC372,PBEC372,PAFC372,PAEC372,PBFC373,PBEC373,PAFC373,PAEC373,PBFC374,PBEC374,PAFC374,PAEC374,PBFC375,PBEC375,PAFC375,PAEC375,PBFC376,PBEC376,PAFC376,PAEC376,PBFC377,PBEC377,PAFC377,PAEC377,PBFC378,PBEC378,PAFC378,PAEC378,PBFC379,PBEC379,PAFC379,PAEC379,PBFC380,PBEC380,PAFC380,PAEC380,PBFC381,PBEC381,PAFC381,PAEC381,PBFC382,PBEC382,PAFC382,PAEC382,PBFC383,PBEC383,PAFC383,PAEC383,PBFC384,PBEC384,PAFC384,PAEC384,PBFC385,PBEC385,PAFC385,PAEC385,PBFC386,PBEC386,PAFC386,PAEC386,PBFC387,PBEC387,PAFC387,PAEC387,PBFC388,PBEC388,PAFC388,PAEC388,PBFC389,PBEC389,PAFC389,PAEC389,PBFC390,PBEC390,PAFC390,PAEC390,PBFC391,PBEC391,PAFC391,PAEC391,PBFC392,PBEC392,PAFC392,PAEC392,PBFC393,PBEC393,PAFC393,PAEC393,PBFC394,PBEC394,PAFC394,PAEC394,PBFC395,PBEC395,PAFC395,PAEC395 |  |  |  |  |  |  |
|  |  |  |  |  | 99 | 620127600-023-G |  | CAP,47uF,+/-20%,X6S,4V,G,SMD0805 | TAIYO ELECTRIC IND.CO.LTD | AMK212BC6476MG-T |  |  |  |  |  |  |  |  |  |
|  |  |  |  |  | 99 | 620127600-026-G |  | CAP,47uF,+/-20%,X6S,4V,G,SMD0805 | SAMSUNG SEMICONDUCTOR | CL21X476MRYNNNE |  |  |  |  |  |  |  |  |  |
|  |  |  |  | 100 | 100 | 62010GS00-015-G |  | CAP,15nF,+/-10%,X7R,25V,G,SMD0603 | MURATA ELEC. NORTH AMERICA | GRM188R71E153K | 8 |  | PBMC400,PBFC400,PBEC400,PBAC400,PAMC400,PAFC400,PAEC400,PAAC400 |  |  |  |  |  |  |
|  |  |  |  | 101 | 101 | 520103B00-185-G |  | Diode,Rectifier&Switching,MMBD1205,100V,200mA,G,SOT-23-3,SMD | FAIRCHILD SEMICONDUCTOR CORP | MMBD1205 | 8 |  | PBMD1,PBFD1,PBED1,PBAD1,PAMD1,PAFD1,PAED1,PAAD1 |  |  |  |  |  |  |
|  |  |  |  | 102 | 102 | 520300600-237-G |  | DIODE,Schottky,BAT54A-7-F,30V,0.2A,G,SOT23-3,SMD | DIODES INCORPORATION | BAT54A-7-F | 8 |  | PBMD3,PBFD3,PBED3,PBAD3,PAMD3,PAFD3,PAED3,PAAD3 |  |  |  |  |  |  |
|  |  |  |  | 103 | 103 | 730100M00-086-G |  | Fuse,Very fast acting,125V,10A,G,SMD | LITTELFUSE FAR EAST PTE LTD | 0451010.MRL | 2 |  | PBAFS1,PAAFS1 |  |  |  |  |  |  |
|  |  |  |  | 104 | 104 | 63035NQ00-029-G |  | IND,0.1uH@100KHz,+/-20%,11.5A,6mOhm,SHLD,G,SMD | VISHAY ENTER TECHNO LOGY.INC | IHLP1616ABERR10M01 | 18 |  | PBML1,PBAL1,PAML1,PAAL1,PBFL2,PBEL2,PAFL2,PAEL2,PBML3,PBFL3,PBEL3,PBAL3,PAML3,PAFL3,PAEL3,PAAL3,PBAL5,PAAL5 |  |  |  |  |  |  |
|  |  |  |  | 105 | 105 | 63035R700-57M-G |  | IND,375nH@1MHz,+/-5%,16A,1.15mOhm,SHLD,G,SMD | Eaton Corporation | CTX01-19603-R | 2 |  | PBAL2,PAAL2 |  |  |  |  |  |  |
|  |  |  |  | 106 | 106 | 510201900-185-G |  | TRANS P,MMBT3906,40V,0.2A,G,SOT23-3,SMD | FAIRCHILD SEMICONDUCTOR CORP | MMBT3906 | 16 |  | PBMQ1,PBFQ1,PBEQ1,PBAQ1,PAMQ1,PAFQ1,PAEQ1,PAAQ1,PBMQ2,PBFQ2,PBEQ2,PBAQ2,PAMQ2,PAFQ2,PAEQ2,PAAQ2 |  |  |  |  |  |  |
|  |  |  |  | 107 | 107 | 51032DL00-237-G |  | MOS N,DMT10H014LSS-13,100V,8.9A,15m@10V,G,SO-8,SMD | DIODES INCORPORATION | DMT10H014LSS-13 | 8 |  | PBMQ10,PBAQ10,PAMQ10,PAAQ10,PBFQ11,PBEQ11,PAFQ11,PAEQ11 |  |  |  |  |  |  |
|  |  |  |  | 108 | 108 | 510100W00-237-G |  | TRANS N,MMBT3904-7-F,40V,0.2A,G,SOT23-3,SMD | DIODES INCORPORATION | MMBT3904-7-F | 18 |  | PBMQ11,PBAQ11,PAMQ11,PAAQ11,PBFQ12,PBEQ12,PAFQ12,PAEQ12,Q8,PHAQ8,Q85,Q86,Q87,Q88,Q89,Q90,Q91,Q92 |  |  |  |  |  |  |
|  |  |  |  |  |  | 510101700-185-G |  | TRANS N,MMBT3904,40V,0.2A,G,SOT23-3,SMD | FAIRCHILD SEMICONDUCTOR CORP | MMBT3904 |  |  |  |  |  |  |  |  |  |
|  |  |  |  | 109 | 109 | 510302R00-185-G |  | MOS N,BSS138,50V,0.22A,6ohm@4.5V,G,SOT23-3,SMD | FAIRCHILD SEMICONDUCTOR CORP | BSS138 | 8 |  | PBFQ10,PBEQ10,PAFQ10,PAEQ10,PBMQ12,PBAQ12,PAMQ12,PAAQ12 |  |  |  |  |  |  |
|  |  |  |  | 110 | 110 | 610108300-017-G |  | RES,0 Ohm,+/-5%,1/10W,G,SMD0603 | KOA SPEER ELECTRONICS, INC. | RK73Z1JTTD | 108 |  | PUAR1,PSIR1,PSAR1,PRAR1,PQAR1,PPAR1,PIAR1,PFAR1,PETR1,PERR1,PEAR1,PBMR1,PBFR1,PBER1,PBAR1,PAMR1,PAFR1,PAER1,PAAR1,PUAR3,PSIR3,PSAR3,PRAR3,PQAR3,PPAR3,PIAR3,PFAR3,PETR3,PERR3,PEAR3,PUAR9,PSIR9,PSAR9,PRAR9,PQAR9,PPAR9,PIAR9,PFAR9,PETR9,PERR9,PEAR9,PBNR10,PANR10,PBNR13,PANR13,PBAR66,PBMR68,PAMR70,PBER71,PAFR71,PAER71,PAAR71,PBFR72,PBMR78,PAMR78,R133,R142,R153,R163,R174,R184,R196,R205,R217,R226,R238,R247,R258,R268,R280,R289,PBER308,PBFR400,PBAR400,PAFR400,PAER400,PAAR400,R488,R497,R508,R518,R529,R539,R551,R560,R572,R581,R593,R602,R614,R623,R635,R644,R1028,R1742,R1743,R1744,R1747,R1748,R1749,R1755,R1761,R1762,R1763,R1764,R1765,R1766,R1767 |  |  |  |  |  |  |
|  |  |  |  |  | 110 | 610108300-024-G |  | RES,0 Ohm,+/-5%,1/10W,G,SMD0603 | PANASONIC INDUSTRIAL CO.,LTD. | ERJ3GEY0R00V |  |  |  |  |  |  |  |  |  |
|  |  |  |  | 111 | 111 | 610107A00-017-G |  | RES,0 Ohm,+/-5%,1/16W,G,SMD0402 | KOA SPEER ELECTRONICS, INC. | RK73Z1ETTP | 712 |  | R1,R2,PSTR2,PSPR2,PSLR2,PSFR2,PSER2,PSDR2,PQPR2,PIPR2,PFPR2,PEPR2,PEER2,PEDR2,PBFR2,PBER2,PBAR2,PAFR2,PAER2,PAAR2,PBNR3,PBER3,PBAR3,PANR3,PAER3,PAAR3,PBNR4,PBFR4,PBAR4,PANR4,PAFR4,PAAR4,R6,PBAR6,PAMR6,R7,PSPR7,PIPR7,PFPR7,PEPR7,PBFR7,PAER7,PAAR7,PSRR8,PSPR8,PSLR8,PSFR8,PSDR8,PQPR8,PIPR8,PFRR8,PFPR8,PEPR8,PEER8,PEDR8,PAFR8,PAER8,PSTR9,PSLR9,PSFR9,PSER9,PSDR9,PQPR9,PFRR9,PEER9,PEDR9,PBER9,PBAR9,PAMR9,PBFR10,PAAR10,PHAR11,PBMR11,PBER11,PAFR11,PUAR12,PSIR12,PSAR12,PRAR12,PQAR12,PPAR12,PIAR12,PHAR12,PFAR12,PETR12,PERR12,PEAR12,PBNR12,PANR12,PBER13,PAAR13,PUAR14,PSRR14,PSPR14,PSAR14,PRAR14,PQAR14,PPAR14,PIPR14,PIAR14,PFPR14,PFAR14,PEPR14,PEAR14,PBMR14,PBFR14,PAFR14,PUAR15,PSTR15,PSRR15,PSLR15,PSFR15,PSER15,PSDR15,PSAR15,PRAR15,PQPR15,PQAR15,PPAR15,PIAR15,PFRR15,PFAR15,PEER15,PEDR15,PEAR15,PBFR15,PBER15,PBAR15,PAFR15,PAER15,PAAR15,PSIR16,PETR16,PERR16,PBMR16,PBAR16,PAMR16,PAER16,PALR17,PSTR18,PSLR18,PSFR18,PSER18,PSDR18,PQPR18,PFRR18,PEER18,PEDR18,PBMR18,PBFR18,PBER18,PBAR18,PAMR18,PAFR18,PAER18,PAAR18,PBLR19,PBNR20,PANR20,PSRR22,PSPR22,PIPR22,PFPR22,PEPR22,PBMR22,PBFR22,PBER22,PBAR22,PAMR22,PAFR22,PAER22,PAAR22,PHAR24,PHAR25,PBMR25,PBFR25,PBER25,PBAR25,PAMR25,PAFR25,PAER25,PAAR25,PBMR28,PBFR28,PBER28,PBAR28,PAMR28,PAFR28,PAER28,PAAR28,R29,R30,PBMR30,PBFR30,PBER30,PBAR30,PAMR30,PAFR30,PAER30,PAAR30,PHAR31,PHAR32,PBMR32,PBFR32,PBER32,PBAR32,PAMR32,PAFR32,PAER32,PAAR32,PHAR33,PBMR33,PBFR33,PBER33,PBAR33,PAMR33,PAFR33,PAER33,PAAR33,PHAR34,PBMR35,PBFR35,PBER35,PBAR35,PAMR35,PAFR35,PAER35,PAAR35,PHAR36,PBMR36,PBFR36,PBER36,PBAR36,PAMR36,PAFR36,PAER36,PAAR36,PBMR38,PBFR38,PBER38,PBAR38,PAMR38,PAFR38,PAER38,PAAR38,PBMR39,PBAR39,PAMR39,PAAR39,PBMR42,PBFR42,PBER42,PBAR42,PAMR42,PAFR42,PAER42,PAAR42,PBMR46,PAMR46,PAER46,PBMR56,PBFR56,PBER56,PBAR56,PAMR56,PAFR56,PAER56,PAAR56,PBMR66,PAMR67,PAAR67,PBAR68,PAMR68,PAAR68,PBAR69,PAAR69,R70,PBMR70,PBAR70,R71,R72,PBAR72,PAAR72,R73,R74,R75,PAFR77,PAER77,PBFR78,PBER78,PAFR78,PAER78,PBMR79,PBFR79,PBER79,PAMR79,PAFR79,PAER79,PBFR80,PBER81,PBAR81,PAFR81,PAER81,PAAR81,PBFR82,PBER82,PAER82,R84,R85,R86,R87,PBMR87,PBER87,PAMR87,PBER89,PBAR89,PAFR89,PAER89,PAAR89,PBFR90,PBAR101,PAAR101,PBMR103,PAMR103,PBMR104,PAMR104,PBER105,PAFR105,PAER105,PBFR106,PBER106,PAFR106,PAER106,PBFR107,PBAR109,PAAR109,PBMR110,PBAR110,PAMR110,PAAR110,PBMR111,PAMR111,PBER112,PAFR112,PAER112,PBFR113,PBER113,PAFR113,PAER113,PBFR114,PBMR115,PAMR115,PBMR116,PBAR116,PAMR116,PAAR116,PBER117,PBAR117,PAFR117,PAER117,PAAR117,PBFR118,PBER118,PAFR118,PAER118,PBFR119,PBAR121,PAAR121,PBAR122,PAAR122,PBFR302,PBER302,PBAR302,PAFR302,PAER302,PAAR302,R303,R306,R308,PBMR308,PBAR308,PAMR308,PAAR308,R309,PBMR309,PBAR309,PAMR309,PAAR309,PBFR310,PAFR310,PAER310,R311,PBER311,R312,PBFR312,PAFR312,PAER312,R313,PBER313,PBAR313,PAAR313,R314,R315,R316,R317,R320,R321,R322,R323,R324,R325,R326,R331,R363,R364,R368,R369,R414,R415,R428,R429,R430,R431,R433,R434,R437,R438,R439,R440,R467,R473,R474,R477,R478,R479,PSUR500,PBNR500,PBMR500,PBFR500,PBER500,PANR500,PAMR500,PAFR500,PAER500,PAAR500,PSUR501,PBNR501,PBMR501,PBFR501,PBER501,PANR501,PAMR501,PAFR501,PAER501,PAAR501,PBAR502,PBAR503,PBFR514,PBER514,PAFR514,PBFR515,PBER515,PAFR515,PAER515,PBFR516,PBER516,PAFR516,PAER516,PAER517,PBFR518,PBER518,PAFR518,PBFR519,PBER519,PAFR519,PAER519,PAER520,PBMR607,PBAR607,PAMR607,PAAR607,PBMR608,PBAR608,PAMR608,PAAR608,R670,R671,R674,R677,R717,R722,R723,R724,R726,R728,R744,R745,R747,R750,R754,R757,R760,R761,R768,R785,R798,R802,R810,R812,R813,R824,R826,R895,R896,R898,R899,R900,R911,R918,R919,R923,R924,R926,R928,R930,R931,R941,R946,R947,R951,R952,R973,R974,R979,R987,R1004,R1005,R1073,R1082,R1086,R1091,R1099,R1100,R1102,R1116,R1117,R1130,R1131,R1132,R1133,R1134,R1143,R1145,R1146,R1158,R1160,R1166,R1167,R1168,R1170,R1177,R1178,R1179,R1180,R1182,R1187,R1188,R1191,R1192,R1194,R1200,R1201,R1203,R1204,R1207,R1208,R1214,R1215,R1216,R1226,R1228,R1233,R1235,R1236,R1238,R1241,R1242,R1243,R1244,R1245,R1246,R1247,R1248,R1249,R1250,R1259,R1260,R1264,R1268,R1272,R1276,R1281,R1282,R1283,R1284,R1285,R1286,R1289,R1290,R1291,R1292,R1293,R1297,R1307,R1314,R1315,R1316,R1317,R1318,R1319,R1320,R1321,R1322,R1330,R1339,R1344,R1360,R1362,R1369,R1370,R1372,R1373,R1375,R1376,R1406,R1407,R1432,R1433,R1434,R1435,R1436,R1437,R1438,R1439,R1442,R1443,R1472,R1473,R1478,R1491,R1496,R1497,R1501,R1502,R1503,R1510,R1514,R1522,R1527,R1528,R1531,R1532,R1599,R1600,R1720,R1721,R1722,R1724,R1725,R1752,R1753,R1776,R1787,R1788,R1803,R1804,R1805,R1807,R1808,R1809,R1810,R1812,R1813,R1814,R1815,R1816,R1817,R1818,R1819,R1825,R1826,R1832,R1833,R1835,R1840,R1841,R1842,PSPR3001,PIPR3001,PFPR3001,PEPR3001,PSPR3002,PIPR3002,PFPR3002,PEPR3002,PSRR3003,PSPR3003,PIPR3003,PFPR3003,PEPR3003,PSRR3005,PSRR3008 |  |  |  |  |  |  |
|  |  |  |  |  | 111 | 610107A00-024-G |  | RES,0 Ohm,+/-5%,1/16W,G,SMD0402 | PANASONIC INDUSTRIAL CO.,LTD. | ERJ2GE0R00X |  |  |  |  |  |  |  |  |  |
|  |  |  |  |  | 111 | 610107A00-029-G |  | RES,0 Ohm,+/-5%,1/16W,G,SMD0402 | VISHAY ENTER TECHNO LOGY.INC | CRCW04020000Z0ED |  |  |  |  |  |  |  |  |  |
|  |  |  |  | 112 | 112 | 61010PS00-017-G |  | RES,200KOhm,+/-1%,1/16W,G,SMD0402 | KOA SPEER ELECTRONICS, INC. | RK73H1ETTP2003F | 48 |  | PBER7,PAMR7,PAMR8,PAFR9,PAFR10,PAER10,PBAR11,PAER11,PBFR12,PBAR12,PAAR12,PBMR13,PBFR13,PBER14,PAAR14,PBMR15,PBMR17,PBFR17,PBER17,PBAR17,PAMR17,PAFR17,PAER17,PAAR17,PBMR21,PBFR21,PBER21,PBAR21,PAMR21,PAFR21,PAER21,PAAR21,PBMR24,PBFR24,PBER24,PBAR24,PAMR24,PAFR24,PAER24,PAAR24,PBMR27,PBFR27,PBER27,PBAR27,PAMR27,PAFR27,PAER27,PAAR27 |  |  |  |  |  |  |
|  |  |  |  |  | 112 | 61010PS00-029-G |  | RES,200KOhm,+/-1%,1/16W,G,SMD0402 | VISHAY | CRCW0402200KFKED |  |  |  |  |  |  |  |  |  |
|  |  |  |  | 113 | 113 | 61100YD00-017-G |  | RES,9.53KOhm,+/-0.1%,1/16W,G,SMD0402 | KOA SPEER ELECTRONICS, INC. | RN731ETTP9531B25 | 2 |  | PBAR26,PAAR26 |  |  |  |  |  |  |
|  |  |  |  |  | 113 | 61100YD00-024-G |  | RES,9.53KOhm,+/-0.1%,1/16W,G,SMD0402 | PANASONIC | ERA2AEB9531X |  |  |  |  |  |  |  |  |  |
|  |  |  |  | 114 | 114 | 611003D00-017-G |  | RES,1KOhm,+/-0.1%,1/16W,G,SMD0402 | KOA SPEER ELECTRONICS, INC. | RN731ETTP1001B25 | 16 |  | PBMR34,PBFR34,PBER34,PBAR34,PAMR34,PAFR34,PAER34,PAAR34,PBMR55,PBFR55,PBER55,PBAR55,PAMR55,PAFR55,PAER55,PAAR55 |  |  |  |  |  |  |
|  |  |  |  | 115 | 115 | 61010L300-017-G |  | RES,1KOhm,+/-1%,1/16W,G,SMD0402 | KOA SPEER ELECTRONICS, INC. | RK73H1ETTP1001F | 44 |  | PHAR9,PALR16,PBLR18,PBNR21,PANR21,PHAR38,PBMR40,PBFR40,PBER40,PBAR40,PAMR40,PAFR40,PAER40,PAAR40,PBMR303,PBFR303,PBER303,PBAR303,PAMR303,PAFR303,PAER303,PAAR303,R678,R679,R865,R866,R1155,R1169,R1181,R1193,R1205,R1217,R1258,R1329,R1333,R1334,R1335,R1498,R1500,R1729,R1733,R1737,R1741,R1824 |  |  |  |  |  |  |
|  |  |  |  |  | 115 | 61010L300-024-G |  | RES,1KOhm,+/-1%,1/16W,G,SMD0402 | PANASONIC INDUSTRIAL CO.,LTD. | ERJ2RKF1001X |  |  |  |  |  |  |  |  |  |
|  |  |  |  |  | 115 | 61010L300-029-G |  | RES,1KOhm,+/-1%,1/16W,G,SMD0402 | VISHAY ENTER TECHNO LOGY.INC | CRCW04021K00FKED |  |  |  |  |  |  |  |  |  |
|  |  |  |  | 116 | 116 | 611008W00-017-G |  | RES,73.2KOhm,+/-0.1%,1/16W,G,SMD0402 | KOA SPEER ELECTRONICS, INC. | RN731ETTP7322B25 | 8 |  | PBMR41,PBFR41,PBER41,PBAR41,PAMR41,PAFR41,PAER41,PAAR41 |  |  |  |  |  |  |
|  |  |  |  | 117 | 117 | 610103Y00-017-G |  | RES,10 Ohm,+/-1%,1/10W,G,SMD0603 | KOA SPEER ELECTRONICS, INC. | RK73H1JTTD10R0F | 16 |  | PHAR8,PHAR14,PHAR15,PBMR45,PBAR45,PAMR45,PAER45,PAAR45,PBMR99,PAMR99,PBER101,PAFR101,PAER101,PBFR102,PBAR105,PAAR105 |  |  |  |  |  |  |
|  |  |  |  |  | 117 | 610103Y00-024-G |  | RES,10 Ohm,+/-1%,1/10W,G,SMD0603 | PANASONIC INDUSTRIAL CO.,LTD. | ERJ3EKF10R0V |  |  |  |  |  |  |  |  |  |
|  |  |  |  | 118 | 118 | 61010LD00-017-G |  | RES,6.8KOhm,+/-1%,1/16W,G,SMD0402 | KOA SPEER ELECTRONICS, INC. | RK73H1ETTP6801F | 2 |  | PBAR47,PAAR47 |  |  |  |  |  |  |
|  |  |  |  |  | 118 | 61010LD00-024-G |  | RES,6.8KOhm,+/-1%,1/16W,G,SMD0402 | PANASONIC INDUSTRIAL CO.,LTD. | ERJ2RKF6801X |  |  |  |  |  |  |  |  |  |
|  |  |  |  | 119 | 119 | 61011MC02-017-G |  | Res,374 Ohm,+/-1%,1/16W,G,SMD0402 | KOA SPEER ELECTRONICS, INC. | RK73H1ETTP3740F | 8 |  | PBMR54,PBFR54,PBER54,PBAR54,PAMR54,PAFR54,PAER54,PAAR54 |  |  |  |  |  |  |
|  |  |  |  |  | 119 | 61011MC00-024-G |  | RES,thick film,374Ohm,+/-1%,1/16W,SMD0402,G | PANASONIC INDUSTRIAL CO.,LTD. | ERJ2RKF3740X |  |  |  |  |  |  |  |  |  |
|  |  |  |  |  | 119 | 61011MC00-029-G |  | RES,thick film,374Ohm,+/-1%,1/16W,SMD0402,G | VISHAY ENTER TECHNO LOGY.INC | CRCW0402374RFKED |  |  |  |  |  |  |  |  |  |
|  |  |  |  | 120 | 120 | 61100QV00-017-G |  | RES,49.9 Ohm,+/-0.5%,1/16W,G,SMD0402 | KOA SPEER ELECTRONICS, INC. | RN731ETTP49R9D50 | 8 |  | PBAR57,PAAR57,R932,R980,R981,R982,R983,R984 |  |  |  |  |  |  |
|  |  |  |  | 121 | 121 | 61100QG00-017-G |  | RES,649 Ohm,+/-0.1%,1/16W,G,SMD0402 | KOA SPEER ELECTRONICS, INC. | RN731ETTP6490B25 | 2 |  | PBAR61,PAAR61 |  |  |  |  |  |  |
|  |  |  |  |  | 121 | 61100QG00-024-G |  | RES,649 Ohm,+/-0.1%,1/16W,G,SMD0402 | PANASONIC INDUSTRIAL CO.,LTD. | ERA2AEB6490X |  |  |  |  |  |  |  |  |  |
|  |  |  |  |  | 121 | 61100QG00-029-G |  | RES,649 Ohm,+/-0.1%,1/16W,G,SMD0402 | VISHAY ENTER TECHNO LOGY.INC | TNPW0402649RBEED |  |  |  |  |  |  |  |  |  |
|  |  |  |  | 122 | 122 | 610113800-017-G |  | RES,10 Ohm,+/-1%,1/16W,G,SMD0402 | KOA SPEER ELECTRONICS, INC. | RK73H1ETTP10R0F | 31 |  | PALR19,PALR20,PBLR23,PBLR24,PBFR45,PBER45,PAFR45,PBER61,PAFR61,PAER61,PBFR62,PBER62,PAFR62,PAER62,PBMR63,PBFR63,PBAR63,PAMR63,PAAR63,PBMR64,PBAR64,PAMR64,PAAR64,PBER93,PAFR93,PAER93,PBFR94,PBER96,PAFR96,PAER96,PBFR97 |  |  |  |  |  |  |
|  |  |  |  | 123 | 123 | 61100AE00-017-G |  | RES,8mOhm,+/-1%,2W,G,SMD2512 | KOA SPEER ELECTRONICS, INC. | TLR3AWDTE8L00F75 | 2 |  | PBAR65,PAAR65 |  |  |  |  |  |  |
|  |  |  |  |  | 123 | ERJMP4PF8M0U |  | RES,8mOhm,+/-1%,2W,G,SMD2512 | PANASONIC INDUSTRIAL CO.,LTD. | ERJMP4PF8M0U |  |  |  |  |  |  |  |  |  |
|  |  |  |  |  | 123 | 610606100-029-G |  | RES,8mOhm,+/-1%,2W,G,SMD2512 | VISHAY ENTER TECHNO LOGY.INC | WSL25128L000FEA18 |  |  |  |  |  |  |  |  |  |
|  |  |  |  | 124 | 124 | 61010RW00-017-G |  | RES,23.2KOhm,+/-1%,1/10W,G,SMD0603 | KOA SPEER ELECTRONICS, INC. | RK73H1JTTD2322F | 12 |  | PBER66,PAFR66,PAER66,PAAR66,PBFR67,PBER67,PBAR67,PAFR67,PAER67,PBFR68,PBAR79,PAAR79 |  |  |  |  |  |  |
|  |  |  |  |  | 124 | 61010RW00-029-G |  | RES,23.2KOhm,+/-1%,1/10W,G,SMD0603 | VISHAY ENTER TECHNO LOGY.INC | CRCW060323K2FKEA |  |  |  |  |  |  |  |  |  |
|  |  |  |  |  | 124 | 61010RW00-024-G |  | RES,23.2KOhm,+/-1%,1/10W,G,SMD0603 | PANASONIC INDUSTRIAL CO.,LTD. | ERJ3EKF2322V |  |  |  |  |  |  |  |  |  |
|  |  |  |  | 125 | 125 | 610108U00-017-G |  | RES,10KOhm,+/-1%,1/10W,G,SMD0603 | KOA SPEER ELECTRONICS, INC. | RK73H1JTTD1002F | 14 |  | PBER72,PAFR72,PAER72,PBFR73,PBMR74,PAMR74,PBMR77,PBAR77,PAMR77,PAAR77,PBER84,PAFR84,PAER84,PBFR85 |  |  |  |  |  |  |
|  |  |  |  |  | 125 | 610108U00-024-G |  | RES,10KOhm,+/-1%,1/10W,G,SMD0603 | PANASONIC INDUSTRIAL CO.,LTD. | ERJ3EKF1002V |  |  |  |  |  |  |  |  |  |
|  |  |  |  | 126 | 126 | 61010G500-017-G |  | RES,10KOhm,+/-1%,1/16W,G,SMD0402 | KOA SPEER ELECTRONICS, INC. | RK73H1ETTP1002F | 102 |  | PANR5,PSTR6,PSLR6,PSFR6,PSER6,PSDR6,PQPR6,PFRR6,PEER6,PEDR6,PBNR6,PUAR7,PSIR7,PSAR7,PRAR7,PQAR7,PPAR7,PIAR7,PFAR7,PETR7,PERR7,PEAR7,PHAR22,PHAR23,PHAR39,PBER74,PAFR74,PAER74,PBMR75,PBFR75,PAMR75,PBAR78,PAAR78,PBMR300,PBFR300,PBER300,PBAR300,PAMR300,PAFR300,PAER300,PAAR300,PBMR305,PBFR305,PBER305,PBAR305,PAMR305,PAFR305,PAER305,PAAR305,PBMR306,PBFR306,PBER306,PBAR306,PAMR306,PAFR306,PAER306,PAAR306,PBMR307,PBFR307,PBER307,PBAR307,PAMR307,PAFR307,PAER307,PAAR307,R330,R351,R353,R357,R359,R480,R481,R482,R483,R719,R864,R906,R914,R912,R913,R916,R917,R920,R1075,R1076,R1077,R1078,R1118,R1136,R1137,R1441,R1482,R1490,R1519,R1534,R1535,R1536,R1537,R1538,R1539,R1540,PSRR3001 |  |  |  |  |  |  |
|  |  |  |  |  | 126 | 61010G500-029-G |  | RES,10KOhm,+/-1%,1/16W,G,SMD0402 | VISHAY ENTER TECHNO LOGY.INC | CRCW040210K0FKED |  |  |  |  |  |  |  |  |  |
|  |  |  |  |  | 126 | 61010G500-024-G |  | RES,10KOhm,+/-1%,1/16W,G,SMD0402 | PANASONIC INDUSTRIAL CO.,LTD. | ERJ2RKF1002X |  |  |  |  |  |  |  |  |  |
|  |  |  |  | 127 | 127 | 610107200-017-G |  | RES,8.25KOhm,+/-1%,1/10W,G,SMD0603 | KOA SPEER ELECTRONICS, INC. | RK73H1JTTD8251F | 2 |  | PBAR80,PAAR80 |  |  |  |  |  |  |
|  |  |  |  | 128 | 128 | 61011A500-017-G |  | RES,1.74KOhm,+/-1%,1/16W,G,SMD0402 | KOA SPEER ELECTRONICS, INC. | RK73H1ETTP1741F | 8 |  | PBMR81,PAMR81,PBER83,PAFR83,PAER83,PBFR84,PBAR84,PAAR84 |  |  |  |  |  |  |
|  |  |  |  |  | 128 | 61011A500-024-G |  | RES,1.74KOhm,+/-1%,1/16W,G,SMD0402 | PANASONIC INDUSTRIAL CO.,LTD. | ERJ2RKF1741X |  |  |  |  |  |  |  |  |  |
|  |  |  |  | 129 | 129 | 61100LR00-017-G |  | RES,100 Ohm,+/-1%,1/16W,G,SMD0402 | KOA SPEER ELECTRONICS, INC. | RN731ETTP1000F50 | 31 |  | PSPR6,PIPR6,PFPR6,PEPR6,PALR14,PALR15,PBLR20,PBLR21,PBER68,PBMR82,PAMR82,PBAR85,PAAR85,PAFR87,PAER87,PBFR88,PBMR91,PAMR91,PBAR93,PAAR93,PBMR94,PAMR94,PBAR96,PAAR96,R1265,R1269,R1273,R1277,R1484,R1745,R1785 |  |  |  |  |  |  |
|  |  |  |  | 130 | 130 | 61010CB00-017-G |  | RES,49.9 Ohm,+/-1%,1/10W,G,SMD0603 | KOA SPEER ELECTRONICS, INC. | RK73H1JTTD49R9F | 8 |  | PBER85,PAFR85,PBMR86,PBFR86,PBAR86,PAMR86,PAAR86,PAER672 |  |  |  |  |  |  |
|  |  |  |  |  | 130 | 61010CB00-024-G |  | RES,49.9 Ohm,+/-1%,1/10W,G,SMD0603 | PANASONIC INDUSTRIAL CO.,LTD. | ERJ3EKF49R9V |  |  |  |  |  |  |  |  |  |
|  |  |  |  | 131 | 131 | 610130Y00-017-G |  | RES,1 Ohm,+/-1%,1/3W,G,SMD1206 | KOA SPEER ELECTRONICS, INC. | SR732BTTD1R00F | 11 |  | PHAR4,PBMR90,PAMR90,PBER92,PBAR92,PAFR92,PAER92,PAAR92,PBFR93,PBAR102,PAAR102 |  |  |  |  |  |  |
|  |  |  |  | 132 | 132 | 611003200-017-G |  | RES,10KOhm,+/-0.1%,1/16W,G,SMD0402 | KOA SPEER ELECTRONICS, INC. | RN731ETTP1002B25 | 34 |  | PBMR26,PAMR26,PBMR97,PAMR97,PBMR98,PAMR98,PBER99,PAFR99,PAER99,PBMR100,PBFR100,PBER100,PAMR100,PAFR100,PAER100,PBFR101,PBMR102,PBER102,PAMR102,PAFR102,PAER102,PBFR103,PBAR103,PAAR103,PBER104,PBAR104,PAFR104,PAER104,PAAR104,PBFR105,PBAR106,PAAR106,PBAR108,PAAR108 |  |  |  |  |  |  |
|  |  |  |  |  |  | 611003200-024-G |  | RES,10KOhm,+/-0.1%,1/16W,G,SMD0402 | PANASONIC | ERA2AEB103X |  |  |  |  |  |  |  |  |  |
|  |  |  |  | 133 | 133 | 61011B300-017-G |  | RES,1MOhm,+/-1%,1/16W,G,SMD0402 | KOA SPEER ELECTRONICS, INC. | RK73H1ETTP1004F | 8 |  | PBMR107,PAMR107,PBER109,PAFR109,PAER109,PBFR110,PBAR113,PAAR113 |  |  |  |  |  |  |
|  |  |  |  |  | 133 | 61011B300-029-G |  | RES,1MOhm,+/-1%,1/16W,G,SMD0402 | VISHAY | CRCW04021M00FKED |  |  |  |  |  |  |  |  |  |
|  |  |  |  | 134 | 134 | 61011GU00-017-G |  | RES,274 Ohm,+/-1%,1/16W,G,SMD0402 | KOA SPEER ELECTRONICS, INC. | RK73H1ETTP2740F | 8 |  | PBMR109,PAMR109,PBER111,PAFR111,PAER111,PBFR112,PBAR115,PAAR115 |  |  |  |  |  |  |
|  |  |  |  |  | 134 | 61011GU00-029-G |  | RES,274 Ohm,+/-1%,1/16W,G,SMD0402 | VISHAY | CRCW0402274RFKED |  |  |  |  |  |  |  |  |  |
|  |  |  |  | 135 | 135 | 61100RU00-017-G |  | RES,59 Ohm,+/-1%,1/16W,G,SMD0402 | KOA SPEER ELECTRONICS, INC. | RN731ETTP59R0F25 | 8 |  | PBMR113,PAMR113,PBER115,PAFR115,PAER115,PBFR116,PBAR119,PAAR119 |  |  |  |  |  |  |
|  |  |  |  | 136 | 136 | 610114P00-017-G |  | RES,715 Ohm,+/-1%,1/16W,G,SMD0402 | KOA SPEER ELECTRONICS, INC. | RK73H1ETTP7150F | 8 |  | PBMR117,PAMR117,PBER119,PAFR119,PAER119,PBFR120,PBAR123,PAAR123 |  |  |  |  |  |  |
|  |  |  |  |  | 136 | 610114P00-024-G |  | RES,715 Ohm,+/-1%,1/16W,G,SMD0402 | PANASONIC | ERJ2RKF7150X |  |  |  |  |  |  |  |  |  |
|  |  |  |  | 137 | 137 | 61011L200-017-G |  | RES,3.65KOhm,+/-1%,1/16W,G,SMD0402 | KOA SPEER ELECTRONICS, INC. | RK73H1ETTP3651F | 9 |  | PHAR79,PBMR118,PAMR118,PBER120,PAFR120,PAER120,PBFR121,PBAR124,PAAR124 |  |  |  |  |  |  |
|  |  |  |  |  | 137 | 61011L200-029-G |  | RES,3.65KOhm,+/-1%,1/16W,G,SMD0402 | VISHAY | 61011L200-029-G |  |  |  |  |  |  |  |  |  |
|  |  |  |  | 138 | 138 | 61011BH00-017-G |  | RES,22.1 Ohm,+/-1%,1/16W,G,SMD0402 | KOA SPEER ELECTRONICS, INC. | RK73H1ETTP22R1F | 4 |  | PBMR304,PBAR304,PAMR304,PAAR304 |  |  |  |  |  |  |
|  |  |  |  |  | 138 | 61011BH00-024-G |  | RES,22.1 Ohm,+/-1%,1/16W,G,SMD0402 | PANASONIC | ERJ2RKF22R1X |  |  |  |  |  |  |  |  |  |
|  |  |  |  |  | 138 | 61011BH00-029-G |  | RES,22.1 Ohm,+/-1%,1/16W,G,SMD0402 | VISHAY | CRCW040222R1FKED |  |  |  |  |  |  |  |  |  |
|  |  |  |  | 139 | 139 | 61012JH00-017-G |  | RES,470 Ohm,+/-5%,1/8W,G,SMD0805 | KOA SPEER ELECTRONICS, INC. | RK73B2ATTD471J | 37 |  | PUAR13,PSAR13,PRAR13,PQAR13,PPAR13,PIAR13,PFAR13,PEAR13,PSIR14,PETR14,PERR14,PALR18,PSTR20,PSLR20,PSFR20,PSER20,PSDR20,PQPR20,PFRR20,PEER20,PEDR20,PBLR22,PBMR452,PBNR502,PBFR502,PBER502,PANR502,PAMR502,PAFR502,PAAR502,PBAR504,PAER514,PSPR3000,PIPR3000,PFPR3000,PEPR3000,PSRR3009 |  |  |  |  |  |  |
|  |  |  |  | 140 | 140 | 610114J00-017-G |  | RES,2KOhm,+/-1%,1/16W,G,SMD0402 | KOA SPEER ELECTRONICS, INC. | RK73H1ETTP2001F | 11 |  | R347,R348,R350,PBFR510,PBER510,PAFR510,PAER510,PBMR600,PBAR600,PAMR600,PAAR600 |  |  |  |  |  |  |
|  |  |  |  |  | 140 | 610114J00-024-G |  | RES,2KOhm,+/-1%,1/16W,G,SMD0402 | PANASONIC INDUSTRIAL CO.,LTD. | ERJ2RKF2001X |  |  |  |  |  |  |  |  |  |
|  |  |  |  |  | 140 | 610114J00-029-G |  | RES,2KOhm,+/-1%,1/16W,G,SMD0402 | VISHAY ENTER TECHNO LOGY.INC | CRCW04022K00FKED |  |  |  |  |  |  |  |  |  |
|  |  |  |  | 141 | 141 | 61010L100-017-G |  | RES,100KOhm,+/-1%,1/16W,G,SMD0402 | KOA SPEER ELECTRONICS, INC. | RK73H1ETTP1003F | 16 |  | PBFR511,PBER511,PAFR511,PAER511,PBMR603,PBAR603,PAMR603,PAAR603,PBMR604,PBAR604,PAMR604,PAAR604,PAFR634,PBFR659,PBER659,PAER684 |  |  |  |  |  |  |
|  |  |  |  |  | 141 | 61010L106-029-G |  | RES,100KOhm,+/-1%,1/16W,G,SMD0402 | VISHAY ENTER TECHNO LOGY.INC | CRCW0402100KFKEDC |  |  |  |  |  |  |  |  |  |
|  |  |  |  |  | 141 | 61010L100-024-G |  | RES,100KOhm,+/-1%,1/16W,G,SMD0402 | PANASONIC INDUSTRIAL CO.,LTD. | ERJ2RKF1003X |  |  |  |  |  |  |  |  |  |
|  |  |  |  | 142 | 142 | 61013A200-017-G |  | RES,6.8 Ohm,+/-1%,1/4W,G,SMD1206 | KOA SPEER ELECTRONICS, INC. | RK73H2BTTD6R80F | 4 |  | PBMR605,PBAR605,PAMR605,PAAR605 |  |  |  |  |  |  |
|  |  |  |  |  | 142 | 61013A200-029-G |  | RES,6.8 Ohm,+/-1%,1/4W,G,SMD1206 | VISHAY | CRCW12066R80FKEA |  |  |  |  |  |  |  |  |  |
|  |  |  |  | 143 | 143 | 61011MG00-017-G |  | RES,42.2KOhm,+/-1%,1/16W,G,SMD0402 | KOA SPEER ELECTRONICS, INC. | RK73H1ETTP4222F | 8 |  | PBFR512,PBER512,PAFR512,PAER512,PBMR606,PBAR606,PAMR606,PAAR606 |  |  |  |  |  |  |
|  |  |  |  | 144 | 144 | ISL68137IRAZ-EVT3 |  | IC,PWM Controller,ISL68137IRAZ-T,G,QFN-48,SMD | INTERSIL CORPORATION | ISL68137IRAZ-EVT3 | 8 |  | PBMU1,PBFU1,PBEU1,PBAU1,PAMU1,PAFU1,PAEU1,PAAU1 |  |  |  |  |  |  |
|  |  |  |  | 145 | 145 | 32040HW00-183-G |  | IC,Current Sensor, INA194AIDBVR ,G,SOT23-5,SMD | TEXAS INSTRUMENTS | INA194AIDBVR | 8 |  | PBMU2,PBFU2,PBEU2,PBAU2,PAMU2,PAFU2,PAEU2,PAAU2 |  |  |  |  |  |  |
|  |  |  |  | 146 | 146 | 880302200-53N-G |  | Converter,input 0V~60V,185W,G,VTM48MP012T130AA0 | Vicor Corporation | VTM48MP012T130AA0 | 4 |  | PBAU4,PAAU4,PBAU6,PAAU6 |  |  |  |  |  |  |
|  |  |  |  | 147 | 147 | 32031MS00-183-G |  | IC,Operation Amplifier,OPA2365AIDR,G,SOIC-8,SMD | TEXAS INSTRUMENTS | OPA2365AIDR | 8 |  | PBMU5,PBFU5,PBEU5,PAMU5,PAFU5,PAEU5,PBAU7,PAAU7 |  |  |  |  |  |  |
|  |  |  |  | 148 | 148 | 62012YR00-015-G |  | CAP,470nF,+/-10%,X7R,100V,G,SMD0805 | MURATA ELEC. NORTH AMERICA | GRM21BR72A474KA73L | 4 |  | PBFC26,PBEC26,PAFC26,PAEC26 |  |  |  |  |  |  |
|  |  |  |  | 149 | 149 | 62011FQ00-015-G |  | CAP,5.6nF,+/-10%,X7R,50V,G,SMD0402 | MURATA ELEC. NORTH AMERICA | GRM155R71H562K | 6 |  | PBFC60,PBEC60,PAFC60,PAEC60,PBMC61,PAMC61 |  |  |  |  |  |  |
|  |  |  |  |  | 149 | 62011FQ00-026-G |  | CAP,5.6nF,+/-10%,X7R,50V,G,SMD0402 | SAMSUNG | CL05B562KB5NNNC |  |  |  |  |  |  |  |  |  |
|  |  |  |  |  | 149 | 62011FQ00-023-G |  | CAP,5.6nF,+/-10%,X7R,50V,G,SMD0402 | TAIYO | UMK105B7562KV-F |  |  |  |  |  |  |  |  |  |
|  |  |  |  | 150 | 150 | 730100L00-086-G |  | Fuse,Very fast acting,125V,5A,G,SMD | LITTELFUSE FAR EAST PTE LTD | 0451005.MRL | 6 |  | PBFFS1,PBEFS1,PAMFS1,PAFFS1,PAEFS1,PAMFS2 |  |  |  |  |  |  |
|  |  |  |  | 151 | 151 | 63035NF00-57M-G |  | IND,1.5uH@100KHz,+/-10%,12A,6mOhm,SHLD,G,SMD | Eaton Corporation | HCV1206-1R5-R | 6 |  | PBFL1,PBEL1,PAFL1,PAEL1,PBML2,PAML2 |  |  |  |  |  |  |
|  |  |  |  | 152 | 152 | 610117V00-017-G |  | RES,680 Ohm,+/-1%,1/16W,G,SMD0402 | KOA SPEER ELECTRONICS, INC. | RK73H1ETTP6800F | 4 |  | PBER4,PAER4,R972,R1090 |  |  |  |  |  |  |
|  |  |  |  | 153 | 153 | 61100RN00-017-G |  | RES,15.4KOhm,+/-0.1%,1/16W,G,SMD0402 | KOA SPEER ELECTRONICS, INC. | RN731ETTP1542B25 | 4 |  | PBFR26,PBER26,PAFR26,PAER26 |  |  |  |  |  |  |
|  |  |  |  | 154 | 154 | 61011DR00-017-G |  | RES,2.2KOhm,+/-1%,1/16W,G,SMD0402 | KOA SPEER ELECTRONICS, INC. | RK73H1ETTP2201F | 16 |  | PBFR47,PBER47,PAFR47,PAER47,R1726,R1727,R1728,R1730,R1731,R1732,R1734,R1735,R1736,R1738,R1739,R1740 |  |  |  |  |  |  |
|  |  |  |  |  | 154 | 61011DR00-029-G |  | RES,2.2KOhm,+/-1%,1/16W,G,SMD0402 | VISHAY ENTER TECHNO LOGY.INC | CRCW04022K20FKED |  |  |  |  |  |  |  |  |  |
|  |  |  |  | 155 | 155 | 61012C600-017-G |  | RES,12.4 Ohm,+/-1%,1/16W,G,SMD0402 | KOA SPEER ELECTRONICS, INC. | RK73H1ETTP12R4F | 4 |  | PBFR57,PBER57,PAFR57,PAER57 |  |  |  |  |  |  |
|  |  |  |  | 156 | 156 | 610108V00-017-G |  | RES,2KOhm,+/-1%,1/10W,G,SMD0603 | KOA SPEER ELECTRONICS, INC. | RK73H1JTTD2001F | 6 |  | PBER58,PAFR58,PAER58,PBFR59,PBMR61,PAMR61 |  |  |  |  |  |  |
|  |  |  |  |  | 156 | 610108V00-024-G |  | RES,2KOhm,+/-1%,1/10W,G,SMD0603 | PANASONIC INDUSTRIAL CO.,LTD. | ERJ3EKF2001V |  |  |  |  |  |  |  |  |  |
|  |  |  |  | 157 | 157 | 611005V00-017-G |  | RES,10mOhm,+/-1%,2W,G,SMD2512 | KOA SPEER ELECTRONICS, INC. | TLR3AWDTE10L0F | 6 |  | PBMR65,PBER65,PAMR65,PAFR65,PAER65,PBFR66 |  |  |  |  |  |  |
|  |  |  |  |  | 157 | 610602300-024-G |  | RES,10mOhm,+/-1%,2W,G,SMD2512 | PANASONIC INDUSTRIAL CO.,LTD. | ERJMP4PF10MU |  |  |  |  |  |  |  |  |  |
|  |  |  |  |  | 157 | 611005V00-029-G |  | RES,thin film,10mOhm,+/-1%,2W,SMD2512,G | VISHAY ENTER TECHNO LOGY.INC | WSL2512R0100FEA18 |  |  |  |  |  |  |  |  |  |
|  |  |  |  | 158 | 158 | 61015NJ00-017-G |  | RES,6.04 Ohm,+/-1%,1/4W,G,SMD1206 | KOA SPEER ELECTRONICS, INC. | RK73H2BTTD6R04F | 4 |  | PBFR513,PBER513,PAFR513,PAER513 |  |  |  |  |  |  |
|  |  |  |  | 159 | 159 | 610117U00-017-G |  | RES,820 Ohm,+/-1%,1/16W,G,SMD0402 | KOA SPEER ELECTRONICS, INC. | RK73H1ETTP8200F | 2 |  | PBFR3,PAFR3 |  |  |  |  |  |  |
|  |  |  |  | 160 | 160 | 880302600-53N-G |  | Converter,input 0V~52V,120W,G,VTM48RP015C076AG0 | Vicor Corporation | VTM48RP015C076AG0 | 4 |  | PBFU4,PBEU4,PAFU4,PAEU4 |  |  |  |  |  |  |
|  |  |  |  | 161 | 161 | 620109700-015-G |  | CAP,3.3nF,+/-10%,X7R,50V,G,SMD0402 | MURATA ELEC. NORTH AMERICA | GRM155R71H332K | 21 |  | PIPC10,PFPC10,PEPC10,PBNC11,PANC11,PBNC13,PANC13,PUAC18,PSAC18,PRAC18,PQAC18,PPAC18,PIAC18,PFAC18,PEAC18,PBNC25,PANC25,PALC35,PALC40,PBLC56,PBLC60 |  |  |  |  |  |  |
|  |  |  |  |  | 161 | 620109700-026-G |  | CAP,3.3nF,+/-10%,X7R,50V,G,SMD0402 | SAMSUNG SEMICONDUCTOR | CL05B332KB5NNNC |  |  |  |  |  |  |  |  |  |
|  |  |  |  |  | 161 | 620109700-023-G |  | CAP,3.3nF,+/-10%,X7R,50V,G,SMD0402 | TAIYO ELECTRIC IND.CO.LTD | UMK105B7332KV-F |  |  |  |  |  |  |  |  |  |
|  |  |  |  | 162 | 162 | 62012GG00-015-G |  | CAP,10uF,+/-10%,X7S,25V,G,SMD0805 | MURATA ELEC. NORTH AMERICA | GRM21BC71E106K | 68 |  | PSTC2,PSLC2,PSFC2,PSEC2,PSDC2,PQPC2,PFRC2,PEEC2,PEDC2,PANC2,PSTC3,PSLC3,PSFC3,PSEC3,PSDC3,PQPC3,PFRC3,PEEC3,PEDC3,PBNC3,PANC3,PBNC4,PANC4,PBNC5,PANC5,PSPC6,PIPC6,PFPC6,PEPC6,PBNC6,PSPC7,PIPC7,PFPC7,PEPC7,PSPC8,PIPC8,PFPC8,PEPC8,PSPC9,PIPC9,PFPC9,PEPC9,PSTC17,PSTC18,PALC38,PALC39,PBLC54,PBLC55,PSPC3004,PIPC3004,PFPC3004,PEPC3004,PSPC3005,PIPC3005,PFPC3005,PEPC3005,PSPC3006,PIPC3006,PFPC3006,PEPC3006,PSPC3007,PIPC3007,PFPC3007,PEPC3007,PSPC3009,PIPC3009,PFPC3009,PEPC3009 |  |  |  |  |  |  |
|  |  |  |  | 163 | 163 | 72010RE00-015-G |  | FB,26 Ohm@100MHz,+/-25%,6A,7mOhm,G,SMD0603 | MURATA ELEC. NORTH AMERICA | BLM18KG260TN1D | 22 |  | PSTL1,PSLL1,PSFL1,PSEL1,PSDL1,PQPL1,PFRL1,PEEL1,PEDL1,PBLL1,PALL1,PUAL2,PSIL2,PSAL2,PRAL2,PQAL2,PPAL2,PIAL2,PFAL2,PERL2,PEAL2,PQPL3 |  |  |  |  |  |  |
|  |  |  |  | 164 | 164 | 630351600-034-G |  | IND,470nH@100KHz,+/-20%,30A,1.68mOhm,SHLD,G,SMD | CYNTEC CO. LTD | PCMB104T-R47MS | 2 |  | PALL2,PBLL4 |  |  |  |  |  |  |
|  |  |  |  | 165 | 165 | 320244200-230-G |  | IC,PWM Controller,ISL99227FRZ-T,G,QFN-32,SMD | INTERSIL CORPORATION | ISL99227FRZ-T | 2 |  | PALU1,PBLU3 |  |  |  |  |  |  |
|  |  |  |  |  | 165 | ISL99227IRZ |  | IC,PWM Controller,ISL99227FRZ-T,G,QFN-32,SMD | INTERSIL CORPORATION | ISL99227IRZ |  |  |  |  |  |  |  |  |  |
|  |  |  |  | 166 | 166 | 61011QD00-017-G |  | RES,330 Ohm,+/-1%,1/16W,G,SMD0402 | KOA SPEER ELECTRONICS, INC. | RK73H1ETTP3300F | 2 |  | PBMR3,PAMR12 |  |  |  |  |  |  |
|  |  |  |  |  | 166 | 61011QD00-029-G |  | RES,330 Ohm,+/-1%,1/16W,G,SMD0402 | VISHAY | CRCW0402330RFKED |  |  |  |  |  |  |  |  |  |
|  |  |  |  | 167 | 167 | 61011HT00-017-G |  | RES,1.8KOhm,+/-1%,1/16W,G,SMD0402 | KOA SPEER ELECTRONICS, INC. | RK73H1ETTP1801F | 2 |  | PBMR47,PAMR47 |  |  |  |  |  |  |
|  |  |  |  |  | 167 | 61011HT00-029-G |  | RES,1.8KOhm,+/-1%,1/16W,G,SMD0402 | VISHAY ENTER TECHNO LOGY.INC | CRCW04021K80FKED |  |  |  |  |  |  |  |  |  |
|  |  |  |  |  | 167 | ERA2RKF1801X |  | RES,1.8KOhm,+/-1%,1/16W,G,SMD0402 | PANASONIC INDUSTRIAL CO.,LTD. | ERA2RKF1801X |  |  |  |  |  |  |  |  |  |
|  |  |  |  | 168 | 168 | 61011GE00-017-G |  | RES,21 Ohm,+/-1%,1/16W,G,SMD0402 | KOA SPEER ELECTRONICS, INC. | RK73H1ETTP21R0F | 2 |  | PBMR57,PAMR57 |  |  |  |  |  |  |
|  |  |  |  |  | 168 | 61011GE00-024-G |  | RES,21 Ohm,+/-1%,1/16W,G,SMD0402 | PANASONIC | ERJ2RKF21R0X |  |  |  |  |  |  |  |  |  |
|  |  |  |  |  | 168 | 61011GE00-029-G |  | RES,21 Ohm,+/-1%,1/16W,G,SMD0402 | VISHAY | CRCW040221R0FKED |  |  |  |  |  |  |  |  |  |
|  |  |  |  | 169 | 169 | 61010R900-017-G |  | RES,27.4KOhm,+/-1%,1/10W,G,SMD0603 | KOA SPEER ELECTRONICS, INC. | RK73H1JTTD2742F | 4 |  | PAMR66,PBMR69,PBMR76,PAMR76 |  |  |  |  |  |  |
|  |  |  |  | 170 | 170 | 62010HR00-015-G |  | CAP,100nF,+/-10%,X7R,50V,G,SMD0603 | MURATA ELEC. NORTH AMERICA | GRM188R71H104K | 13 |  | PUAC8,PSIC8,PSAC8,PRAC8,PQAC8,PPAC8,PIAC8,PFAC8,PETC8,PERC8,PEAC8,PBNC10,PANC10 |  |  |  |  |  |  |
|  |  |  |  |  | 170 | 62010HR00-026-G |  | CAP,100nF,+/-10%,X7R,50V,G,SMD0603 | SAMSUNG SEMICONDUCTOR | CL10B104KB8NNNC |  |  |  |  |  |  |  |  |  |
|  |  |  |  | 171 | 171 | 630330G00-088-G |  | IND,300nH@100KHz,+/-10%,32.5A,304.5uOhm,SHLD,G,SMD | COOPER BUSSMANN, INC. | FP0906R1-R30-R | 2 |  | PBNL1,PANL1 |  |  |  |  |  |  |
|  |  |  |  | 172 | 172 | 61011JH00-017-G |  | RES,19.1KOhm,+/-1%,1/16W,G,SMD0402 | KOA SPEER ELECTRONICS, INC. | RK73H1ETTP1912F | 6 |  | PANR6,PBNR7,R355,R356,R361,R362 |  |  |  |  |  |  |
|  |  |  |  | 173 | 173 | 610114S00-017-G |  | RES,4.99KOhm,+/-1%,1/16W,G,SMD0402 | KOA SPEER ELECTRONICS, INC. | RK73H1ETTP4991F | 3 |  | PFRR3,PBNR5,PANR7 |  |  |  |  |  |  |
|  |  |  |  |  | 173 | 610114S00-024-G |  | RES,4.99KOhm,+/-1%,1/16W,G,SMD0402 | PANASONIC INDUSTRIAL CO.,LTD. | ERJ2RKF4991X |  |  |  |  |  |  |  |  |  |
|  |  |  |  | 174 | 174 | 610114B00-017-G |  | RES,2.49KOhm,+/-1%,1/16W,G,SMD0402 | KOA SPEER ELECTRONICS, INC. | RK73H1ETTP2491F | 2 |  | PBNR11,PANR11 |  |  |  |  |  |  |
|  |  |  |  |  | 174 | 610114B00-024-G |  | RES,2.49KOhm,+/-1%,1/16W,G,SMD0402 | PANASONIC | ERJ2RKF2491X |  |  |  |  |  |  |  |  |  |
|  |  |  |  |  | 174 | 610114B00-029-G |  | RES,2.49KOhm,+/-1%,1/16W,G,SMD0402 | VISHAY | CRCW04022K49FKED |  |  |  |  |  |  |  |  |  |
|  |  |  |  | 175 | 175 | 61011CJ00-017-G |  | RES,365 Ohm,+/-1%,1/16W,G,SMD0402 | KOA SPEER ELECTRONICS, INC. | RK73H1ETTP3650F | 2 |  | PBNR14,PANR14 |  |  |  |  |  |  |
|  |  |  |  |  | 175 | 61011CJ00-024-G |  | RES,365 Ohm,+/-1%,1/16W,G,SMD0402 | PANASONIC | ERJ2RKF3650X |  |  |  |  |  |  |  |  |  |
|  |  |  |  |  | 175 | 61011CJ00-029-G |  | RES,365 Ohm,+/-1%,1/16W,G,SMD0402 | VISHAY | CRCW0402365RFKEDC |  |  |  |  |  |  |  |  |  |
|  |  |  |  | 176 | 176 | 610112G00-017-G |  | RES,20 Ohm,+/-1%,1/16W,G,SMD0402 | KOA SPEER ELECTRONICS, INC. | RK73H1ETTP20R0F | 2 |  | PBNR15,PANR15 |  |  |  |  |  |  |
|  |  |  |  |  | 176 | 610112G00-024-G |  | RES,20 Ohm,+/-1%,1/16W,G,SMD0402 | PANASONIC INDUSTRIAL CO.,LTD. | ERJ2RKF20R0X |  |  |  |  |  |  |  |  |  |
|  |  |  |  | 177 | 177 | 611005R00-017-G |  | RES,100 Ohm,+/-0.1%,1/16W,G,SMD0402 | KOA SPEER ELECTRONICS, INC. | RN731ETTP1000B25 | 5 |  | PSRR16,PBNR16,PANR16,PBNR18,PANR18 |  |  |  |  |  |  |
|  |  |  |  | 178 | 178 | 61011B600-017-G |  | RES,5.36KOhm,+/-1%,1/16W,G,SMD0402 | KOA SPEER ELECTRONICS, INC. | RK73H1ETTP5361F | 2 |  | PBNR17,PANR17 |  |  |  |  |  |  |
|  |  |  |  |  | 178 | 61011B600-024-G |  | RES,5.36KOhm,+/-1%,1/16W,G,SMD0402 | PANASONIC | ERJ2RKF5361X |  |  |  |  |  |  |  |  |  |
|  |  |  |  |  | 178 | 61011B600-029-G |  | RES,5.36KOhm,+/-1%,1/16W,G,SMD0402 | VISHAY | CRCW04025K36FKEDC |  |  |  |  |  |  |  |  |  |
|  |  |  |  | 179 | 179 | 61010LA00-017-G |  | RES,4.7KOhm,+/-1%,1/16W,G,SMD0402 | KOA SPEER ELECTRONICS, INC. | RK73H1ETTP4701F | 156 |  | PSRR20,PBNR23,PANR23,PHAR28,PHAR29,PHAR30,R668,R669,R683,R762,R763,R764,R765,R766,R767,R769,R770,R772,R773,R774,R775,R776,R777,R778,R779,R780,R781,R782,R783,R784,R788,R791,R795,R800,R801,R804,R805,R806,R807,R808,R809,R811,R814,R817,R820,R822,R823,R825,R827,R828,R830,R893,R894,R901,R902,R922,R942,R943,R944,R945,R949,R950,R955,R956,R957,R958,R959,R1129,R1135,R1138,R1148,R1149,R1150,R1151,R1152,R1156,R1159,R1162,R1164,R1165,R1172,R1174,R1175,R1176,R1184,R1185,R1186,R1190,R1195,R1197,R1198,R1199,R1210,R1211,R1212,R1213,R1218,R1219,R1220,R1221,R1222,R1223,R1224,R1240,R1256,R1257,R1263,R1267,R1271,R1275,R1295,R1296,R1460,R1461,R1462,R1463,R1464,R1465,R1466,R1467,R1468,R1469,R1470,R1471,R1474,R1475,R1476,R1477,R1495,R1504,R1507,R1508,R1509,R1511,R1512,R1515,R1520,R1521,R1589,R1590,R1592,R1593,R1603,R1604,R1605,R1606,R1779,R1780,R1781,R1782,R1786,R1789,R1801,R1820,R1821,R1834 |  |  |  |  |  |  |
|  |  |  |  |  | 179 | 61010LA00-029-G |  | RES,4.7KOhm,+/-1%,1/16W,G,SMD0402 | VISHAY | CRCW04024K70FKED |  |  |  |  |  |  |  |  |  |
|  |  |  |  | 180 | 180 | 61011CS00-017-G |  | RES,750KOhm,+/-1%,1/16W,G,SMD0402 | KOA SPEER ELECTRONICS, INC. | RK73H1ETTP7503F | 2 |  | PBNR24,PANR24 |  |  |  |  |  |  |
|  |  |  |  |  |  | 61011CS00-011-G |  | RES,750KOhm,+/-1%,1/16W,G,SMD0402 | YAGEO | RC0402FR-07750KL |  |  |  |  |  |  |  |  |  |
|  |  |  |  | 181 | 181 | 61011BS00-017-G |  | RES,2.05KOhm,+/-1%,1/16W,G,SMD0402 | KOA SPEER ELECTRONICS, INC. | RK73H1ETTP2051F | 1 |  | PANR26 |  |  |  |  |  |  |
|  |  |  |  |  | 181 | 61011BS00-029-G |  | RES,2.05KOhm,+/-1%,1/16W,G,SMD0402 | VISHAY | CRCW04022K05FKED |  |  |  |  |  |  |  |  |  |
|  |  |  |  | 182 | 182 | 320147Q00-238-G |  | IC,Regulator,IR38064MTRPBF,ADJ,35A,G,QFN-26,SMD | INTERNATIONAL RECTIFIER | IR38064MTRPBF | 2 |  | PBNU1,PANU1 |  |  |  |  |  |  |
|  |  |  |  | 183 | 183 | 610118R00-017-G |  | RES,1.54KOhm,+/-1%,1/16W,G,SMD0402 | KOA SPEER ELECTRONICS, INC. | RK73H1ETTP1541F | 1 |  | PBNR26 |  |  |  |  |  |  |
|  |  |  |  |  | 183 | 610118R00-029-G |  | RES,1.54KOhm,+/-1%,1/16W,G,SMD0402 | VISHAY | CRCW04021K54FKED |  |  |  |  |  |  |  |  |  |
|  |  |  |  | 184 | 184 | 62011F100-015-G |  | CAP,1uF,+/-10%,X7R,25V,G,SMD0603 | MURATA ELEC. NORTH AMERICA | GRM188R71E105K | 12 |  | PUAC1,PSIC1,PSAC1,PRAC1,PQAC1,PPAC1,PIAC1,PFAC1,PETC1,PERC1,PEAC1,PSUC4 |  |  |  |  |  |  |
|  |  |  |  |  | 184 | 62011F100-026-G |  | CAP,1uF,+/-10%,X7R,25V,G,SMD0603 | SAMSUNG SEMICONDUCTOR | CL10B105KA8NNNC |  |  |  |  |  |  |  |  |  |
|  |  |  |  |  | 184 | 62011F100-023-G |  | CAP,1uF,+/-10%,X7R,25V,G,SMD0603 | TAIYO ELECTRIC IND.CO.LTD | TMK107B7105KA-T |  |  |  |  |  |  |  |  |  |
|  |  |  |  | 185 | 185 | 62011DD00-015-G |  | CAP,22uF,+/-10%,X6S,6.3V,G,SMD1206 | MURATA ELEC. NORTH AMERICA | GRM31CC80J226K | 24 |  | PUAC4,PSAC4,PRAC4,PQAC4,PPAC4,PIAC4,PFAC4,PEAC4,PUAC5,PSAC5,PRAC5,PQAC5,PPAC5,PIAC5,PFAC5,PEAC5,PUAC6,PSAC6,PRAC6,PQAC6,PPAC6,PIAC6,PFAC6,PEAC6 |  |  |  |  |  |  |
|  |  |  |  | 186 | 186 | 620119R04-015-G |  | CAP,22uF,+/-20%,X6S,4V,G,SMD0805 | MURATA ELEC. NORTH AMERICA | GRM21BC80G226M | 84 |  | PSLC7,PSFC7,PSEC7,PSDC7,PEEC7,PEDC7,PSLC8,PSFC8,PSEC8,PSDC8,PEEC8,PEDC8,PUAC11,PSLC11,PSIC11,PSFC11,PSEC11,PSDC11,PSAC11,PRAC11,PQAC11,PPAC11,PIAC11,PFAC11,PEEC11,PEDC11,PEAC11,PUAC12,PSLC12,PSIC12,PSFC12,PSEC12,PSDC12,PSAC12,PRAC12,PQAC12,PPAC12,PIAC12,PFAC12,PEEC12,PEDC12,PEAC12,PUAC13,PSIC13,PSAC13,PRAC13,PQAC13,PPAC13,PIAC13,PFAC13,PEAC13,PUAC14,PSIC14,PSAC14,PRAC14,PQAC14,PPAC14,PIAC14,PFAC14,PEAC14,PUAC15,PSLC15,PSIC15,PSFC15,PSEC15,PSDC15,PSAC15,PRAC15,PQAC15,PPAC15,PIAC15,PFAC15,PEEC15,PEDC15,PEAC15,PUAC16,PSIC16,PSAC16,PRAC16,PQAC16,PPAC16,PIAC16,PFAC16,PEAC16 |  |  |  |  |  |  |
|  |  |  |  |  | 186 | 620119R00-023-G |  | CAP,22uF,+/-20%,X6S,4V,G,SMD0805 | TAIYO ELECTRIC IND.CO.LTD | AMK212C6226MG-T |  |  |  |  |  |  |  |  |  |
|  |  |  |  |  | 186 | 620119R00-026-G |  | CAP,22uF,+/-20%,X6S,4V,G,SMD0805 | SAMSUNG SEMICONDUCTOR | CL21X226MRQNNNE |  |  |  |  |  |  |  |  |  |
|  |  |  |  | 187 | 187 | 62012G600-015-G |  | CAP,2.2uF,+/-10%,X7S,25V,G,SMD0603 | MURATA ELEC. NORTH AMERICA | GRM188C71E225K | 11 |  | PUAC19,PSIC19,PSAC19,PRAC19,PQAC19,PPAC19,PIAC19,PFAC19,PETC19,PERC19,PEAC19 |  |  |  |  |  |  |
|  |  |  |  | 188 | 188 | 630335M00-088-G |  | IND,820nH@100KHz,+/-20%,13A,8mOhm,SHLD,G,SMD | COOPER BUSSMANN, INC. | HCM0703-R82-R | 8 |  | PUAL1,PSAL1,PRAL1,PQAL1,PPAL1,PIAL1,PFAL1,PEAL1 |  |  |  |  |  |  |
|  |  |  |  | 189 | 189 | 610114200-017-G |  | RES,10.7KOhm,+/-1%,1/16W,G,SMD0402 | KOA SPEER ELECTRONICS, INC. | RK73H1ETTP1072F | 8 |  | PUAR2,PSAR2,PRAR2,PQAR2,PPAR2,PIAR2,PFAR2,PEAR2 |  |  |  |  |  |  |
|  |  |  |  |  | 189 | 610114200-024-G |  | RES,10.7KOhm,+/-1%,1/16W,G,SMD0402 | PANASONIC | ERJ2RKF1072X |  |  |  |  |  |  |  |  |  |
|  |  |  |  |  | 189 | 610114200-029-G |  | RES,10.7KOhm,+/-1%,1/16W,G,SMD0402 | VISHAY | CRCW040210K7FKED |  |  |  |  |  |  |  |  |  |
|  |  |  |  | 190 | 190 | 611004D00-017-G |  | RES,1.5KOhm,+/-0.1%,1/16W,G,SMD0402 | KOA SPEER ELECTRONICS, INC. | RN731ETTP1501B25 | 16 |  | PUAR4,PSAR4,PRAR4,PQAR4,PPAR4,PIAR4,PFAR4,PEAR4,PUAR6,PSAR6,PRAR6,PQAR6,PPAR6,PIAR6,PFAR6,PEAR6 |  |  |  |  |  |  |
|  |  |  |  |  | 190 | 611004D00-029-G |  | RES,1.5KOhm,+/-0.1%,1/16W,G,SMD0402 | VISHAY | TNPW04021K50BEED |  |  |  |  |  |  |  |  |  |
|  |  |  |  | 191 | 191 | 61011JY00-017-G |  | RES,39.2KOhm,+/-1%,1/16W,G,SMD0402 | KOA SPEER ELECTRONICS, INC. | RK73H1ETTP3922F | 11 |  | PUAR5,PSIR5,PSAR5,PRAR5,PQAR5,PPAR5,PIAR5,PFAR5,PETR5,PERR5,PEAR5 |  |  |  |  |  |  |
|  |  |  |  |  | 191 | 61011JY00-029-G |  | RES,39.2KOhm,+/-1%,1/16W,G,SMD0402 | VISHAY ENTER TECHNO LOGY.INC | CRCW040239K2FKED |  |  |  |  |  |  |  |  |  |
|  |  |  |  | 192 | 192 | 610117F00-017-G |  | RES,5.76KOhm,+/-1%,1/16W,G,SMD0402 | KOA SPEER ELECTRONICS, INC. | RK73H1ETTP5761F | 16 |  | PUAR8,PSAR8,PRAR8,PQAR8,PPAR8,PIAR8,PFAR8,PEAR8,PUAR11,PSAR11,PRAR11,PQAR11,PPAR11,PIAR11,PFAR11,PEAR11 |  |  |  |  |  |  |
|  |  |  |  | 193 | 193 | 610128200-017-G |  | RES,26.1 Ohm,+/-1%,1/16W,G,SMD0402 | KOA SPEER ELECTRONICS, INC. | RK73H1ETTP26R1F | 8 |  | PUAR10,PSAR10,PRAR10,PQAR10,PPAR10,PIAR10,PFAR10,PEAR10 |  |  |  |  |  |  |
|  |  |  |  |  | 193 | 610128200-029-G |  | RES,26.1 Ohm,+/-1%,1/16W,G,SMD0402 | VISHAY | CRCW040226R1FKED |  |  |  |  |  |  |  |  |  |
|  |  |  |  | 194 | 194 | 32012NN00-238-G |  | IC,Regulator,IR3898MTRPBF,6A,1.5MHZ,G,QFN-17,SMD | INTERNATIONAL RECTIFIER | IR3898MTRPBF | 11 |  | PUAU1,PSIU1,PSAU1,PRAU1,PQAU1,PPAU1,PIAU1,PFAU1,PETU1,PERU1,PEAU1 |  |  |  |  |  |  |
|  |  |  |  | 195 | 195 | 62012T300-015-G |  | CAP,1uF,+/-10%,X7S,25V,G,SMD0402 | MURATA ELEC. NORTH AMERICA | GRM155C71E105KE11D | 14 |  | PSTC4,PSLC4,PSFC4,PSEC4,PSDC4,PQPC4,PFRC4,PEEC4,PEDC4,PSPC3003,PIPC3003,PFPC3003,PEPC3003,PSRC3010 |  |  |  |  |  |  |
|  |  |  |  | 196 | 196 | 62012CM01-015-G |  | CAP,10uF,+/-20%,X6S,4V,G,SMD0603 | MURATA ELEC. NORTH AMERICA | GRM188C80G106M | 6 |  | PSLC16,PSFC16,PSEC16,PSDC16,PEEC16,PEDC16 |  |  |  |  |  |  |
|  |  |  |  |  | 196 | 62012CM00-026-G |  | CAP,10uF,+/-20%,X6S,4V,G,SMD0603 | SAMSUNG | CL10X106MR8NNNC |  |  |  |  |  |  |  |  |  |
|  |  |  |  |  | 196 | 62012CM00-023-G |  | CAP,10uF,+/-20%,X6S,4V,G,SMD0603 | TAIYO ELECTRIC IND.CO.LTD | AMK107AC6106MA-T |  |  |  |  |  |  |  |  |  |
|  |  |  |  | 197 | 197 | 63032CD00-088-G |  | IND,2.2uH@100KHz,+/-20%,8A,20mOhm,SHLD,G,SMD | COOPER BUSSMANN, INC. | HCM0703-2R2-R | 5 |  | PETL1,PERL1,PSFL2,PEEL2,PEDL2 |  |  |  |  |  |  |
|  |  |  |  | 198 | 198 | 61011HA00-017-G |  | RES,1 Ohm,+/-1%,1/16W,G,SMD0402 | KOA SPEER ELECTRONICS, INC. | RK73H1ETTP1R00F | 13 |  | PSPR4,PIPR4,PFPR4,PEPR4,PSTR5,PSLR5,PSFR5,PSER5,PSDR5,PQPR5,PFRR5,PEER5,PEDR5 |  |  |  |  |  |  |
|  |  |  |  |  | 198 | 61011HA00-029-G |  | RES,1 Ohm,+/-1%,1/16W,G,SMD0402 | VISHAY ENTER TECHNO LOGY.INC | CRCW04021R00FNED |  |  |  |  |  |  |  |  |  |
|  |  |  |  | 199 | 199 | 611004M00-017-G |  | RES,16.5KOhm,+/-0.1%,1/16W,G,SMD0402 | KOA SPEER ELECTRONICS, INC. | RN731ETTP1652B25 | 9 |  | PSLR17,PSFR17,PSER17,PSDR17,PQPR17,PFRR17,PEER17,PEDR17,PEDR19 |  |  |  |  |  |  |
|  |  |  |  |  | 199 | 611004M00-024-G |  | RES,16.5KOhm,+/-0.1%,1/16W,G,SMD0402 | PANASONIC | ERA2AEB1652X |  |  |  |  |  |  |  |  |  |
|  |  |  |  | 200 | 200 | 32013PD00-238-G |  | IC,Regulator,IR3883MTRPbF,ADJ,3A,G,QFN-16,SMD | INTERNATIONAL RECTIFIER | IR3883MTRPBF | 9 |  | PSTU1,PSLU1,PSFU1,PSEU1,PSDU1,PQPU1,PFRU1,PEEU1,PEDU1 |  |  |  |  |  |  |
|  |  |  |  | 201 | 201 | 611003400-017-G |  | RES,12.7KOhm,+/-0.1%,1/16W,G,SMD0402 | KOA SPEER ELECTRONICS, INC. | RN731ETTP1272B25 | 1 |  | PEER19 |  |  |  |  |  |  |
|  |  |  |  |  | 201 | 611003400-024-G |  | RES,12.7KOhm,+/-0.1%,1/16W,G,SMD0402 | PANASONIC INDUSTRIAL CO.,LTD. | ERA2AEB1272X |  |  |  |  |  |  |  |  |  |
|  |  |  |  |  | 201 | 611003400-029-G |  | RES,12.7KOhm,+/-0.1%,1/16W,G,SMD0402 | VISHAY ENTER TECHNO LOGY.INC | TNPW040212K7BEED |  |  |  |  |  |  |  |  |  |
|  |  |  |  | 202 | 202 | 62120HJ00-022-G |  | ECAP,SPEA,270uF,+/-20%,16V,105C,G,SMD6.3X9.9,ESR<=8mOhm | SANYO ELECTRIC CO., LTD. | 16SVPG270M | 5 |  | PSPCE1,PIPCE1,PFPCE1,PEPCE1,PSUCE4 |  |  |  |  |  |  |
|  |  |  |  | 203 | 203 | 62120CM00-024-G |  | SPEA CAP,220uF,+10%~-35%,6.3V,105C,G,SMD2816,ESR<=15mOhm | PANASONIC INDUSTRIAL CO.,LTD. | EEFCX0J221YR | 14 |  | PSRCE3000,PSRCE3001,PSPCE3003,PIPCE3003,PFPCE3003,PEPCE3003,PSPCE3004,PIPCE3004,PFPCE3004,PEPCE3004,PSPCE3005,PIPCE3005,PFPCE3005,PEPCE3005 |  |  |  |  |  |  |
|  |  |  |  | 204 | 204 | 63032CC00-088-G |  | IND,1uH@100KHz,+/-20%,11A,10mOhm,SHLD,G,SMD | COOPER BUSSMANN, INC. | HCM0703-1R0-R | 4 |  | PSPL1,PIPL1,PFPL1,PEPL1 |  |  |  |  |  |  |
|  |  |  |  | 205 | 205 | 630341400-088-G |  | IND,22nH@1MHz,+/-20%,19A,368uOhm,SHLD,G,SMD | COOPER BUSSMANN, INC. | FP0404R1-R022-R | 4 |  | PSPL2,PIPL2,PFPL2,PEPL2 |  |  |  |  |  |  |
|  |  |  |  | 206 | 206 | 61011H300-017-G |  | RES,316 Ohm,+/-1%,1/16W,G,SMD0402 | KOA SPEER ELECTRONICS, INC. | RK73H1ETTP3160F | 4 |  | PSPR5,PIPR5,PFPR5,PEPR5 |  |  |  |  |  |  |
|  |  |  |  |  | 206 | 61011H300-029-G |  | RES,316 Ohm,+/-1%,1/16W,G,SMD0402 | VISHAY | CRCW0402316RFKEDC |  |  |  |  |  |  |  |  |  |
|  |  |  |  | 207 | 207 | 610116R00-017-G |  | RES,14.3KOhm,+/-1%,1/16W,G,SMD0402 | KOA SPEER ELECTRONICS, INC. | RK73H1ETTP1432F | 4 |  | PSPR9,PIPR9,PFPR9,PEPR9 |  |  |  |  |  |  |
|  |  |  |  |  | 207 | 610116R00-029-G |  | RES,thick film,14.3KOhm,+/-1%,1/16W,SMD0402,G | VISHAY ENTER TECHNO LOGY.INC | CRCW040214K3FKED |  |  |  |  |  |  |  |  |  |
|  |  |  |  | 208 | 208 | 61100QQ00-017-G |  | RES,9.76KOhm,+/-0.1%,1/16W,G,SMD0402 | KOA SPEER ELECTRONICS, INC. | RN731ETTP9761B25 | 4 |  | PSPR10,PIPR10,PFPR10,PEPR10 |  |  |  |  |  |  |
|  |  |  |  |  | 208 | 61100QQ00-024-G |  | RES,9.76KOhm,+/-0.1%,1/16W,G,SMD0402 | PANASONIC INDUSTRIAL CO.,LTD. | ERA2AEB9761X |  |  |  |  |  |  |  |  |  |
|  |  |  |  |  | 208 | 61100QQ00-029-G |  | RES,9.76KOhm,+/-0.1%,1/16W,G,SMD0402 | VISHAY ENTER TECHNO LOGY.INC | TNPW04029K76BEED |  |  |  |  |  |  |  |  |  |
|  |  |  |  | 209 | 209 | 610112J00-017-G |  | RES,200 Ohm,+/-1%,1/16W,G,SMD0402 | KOA SPEER ELECTRONICS, INC. | RK73H1ETTP2000F | 15 |  | PSPR11,PIPR11,PFPR11,PEPR11,R680,R688,R689,R746,R755,R756,R758,R759,R771,R1487,R1541 |  |  |  |  |  |  |
|  |  |  |  |  | 209 | 610112J00-029-G |  | RES,200 Ohm,+/-1%,1/16W,G,SMD0402 | VISHAY ENTER TECHNO LOGY.INC | CRCW0402200RFKED |  |  |  |  |  |  |  |  |  |
|  |  |  |  |  | 209 | 610112J00-024-G |  | RES,200 Ohm,+/-1%,1/16W,G,SMD0402 | PANASONIC INDUSTRIAL CO.,LTD. | ERJ2RKF2000X |  |  |  |  |  |  |  |  |  |
|  |  |  |  | 210 | 210 | 61011MU00-017-G |  | RES,48.7KOhm,+/-1%,1/16W,G,SMD0402 | KOA SPEER ELECTRONICS, INC. | RK73H1ETTP4872F | 5 |  | PSRR7,PSPR15,PIPR15,PFPR15,PEPR15 |  |  |  |  |  |  |
|  |  |  |  |  | 210 | 61011MU00-029-G |  | RES,48.7KOhm,+/-1%,1/16W,G,SMD0402 | VISHAY ENTER TECHNO LOGY.INC | CRCW040248K7FKED |  |  |  |  |  |  |  |  |  |
|  |  |  |  | 211 | 211 | 32013HH00-238-G |  | IC,Regulator,IR3447MTRPBF,ADJ,25A,G,PQFN-33 | INTERNATIONAL RECTIFIER | IR3447MTRPBF | 4 |  | PSPU1,PIPU1,PFPU1,PEPU1 |  |  |  |  |  |  |
|  |  |  |  | 212 | 212 | 62011M802-015-G |  | CAP,62pF,+/-5%,NPO(C0G),50V,G,SMD0402 | MURATA ELEC. NORTH AMERICA | GRM1555C1H620JA01D | 2 |  | PSRC3,PERC3 |  |  |  |  |  |  |
|  |  |  |  | 213 | 213 | 62013BP00-015-G |  | CAP,22uF,+/-20%,X6S,25V,G,SMD1206 | MURATA ELEC. NORTH AMERICA | GRM31CC81E226ME11L | 10 |  | PSIC4,PETC4,PERC4,PSIC5,PETC5,PERC5,PSIC6,PETC6,PERC6,PETC22 |  |  |  |  |  |  |
|  |  |  |  | 214 | 214 | 62013BN00-015-G |  | CAP,4.3nF,+/-10%,X7R,50V,G,SMD0402 | MURATA ELEC. NORTH AMERICA | GRM155R71H432KA01D | 1 |  | PERC7 |  |  |  |  |  |  |
|  |  |  |  | 215 | 215 | 62012PT00-015-G |  | CAP,22uF,+/-20%,X6S,16V,G,SMD0805 | MURATA ELEC. NORTH AMERICA | GRM21BC81C226M | 35 |  | PSTC7,PQPC7,PFRC7,PSTC8,PQPC8,PFRC8,PSRC10,PSTC11,PSRC11,PQPC11,PFRC11,PETC11,PERC11,PSTC12,PSRC12,PQPC12,PFRC12,PETC12,PERC12,PSRC13,PETC13,PERC13,PETC14,PERC14,PSTC15,PQPC15,PFRC15,PETC15,PERC15,PETC16,PERC16,PSRC3012,PSRC3013,PSRC3014,PSRC3015 |  |  |  |  |  |  |
|  |  |  |  |  | 215 | 62012PT00-023-G |  | CAP,22uF,+/-20%,X6S,16V,G,SMD0805 | TAIYO ELECTRIC IND.CO.LTD | EDK212BC6226MG-T |  |  |  |  |  |  |  |  |  |
|  |  |  |  | 216 | 216 | 61011PE00-017-G |  | RES,8.87KOhm,+/-1%,1/16W,G,SMD0402 | KOA SPEER ELECTRONICS, INC. | RK73H1ETTP8871F | 2 |  | PERR2,PHAR35 |  |  |  |  |  |  |
|  |  |  |  |  | 216 | 61011PE00-024-G |  | RES,8.87KOhm,+/-1%,1/16W,G,SMD0402 | VISHAY | ERJ2RKF8871X |  |  |  |  |  |  |  |  |  |
|  |  |  |  |  | 216 | 61011PE00-029-G |  | RES,8.87KOhm,+/-1%,1/16W,G,SMD0402 | PANASONIC | CRCW04028K87FKEDC |  |  |  |  |  |  |  |  |  |
|  |  |  |  | 217 | 217 | 61100JA00-017-G |  | RES,8.66KOhm,+/-0.1%,1/16W,G,SMD0402 | KOA SPEER ELECTRONICS, INC. | RN731ETTP8661B25 | 2 |  | PERR8,PERR11 |  |  |  |  |  |  |
|  |  |  |  |  | 217 | 61100JA00-024-G |  | RES,8.66KOhm,+/-0.1%,1/16W,G,SMD0402 | PANASONIC INDUSTRIAL CO.,LTD. | ERA2AEB8661X |  |  |  |  |  |  |  |  |  |
|  |  |  |  |  | 217 | 61100JA00-029-G |  | RES,8.66KOhm,+/-0.1%,1/16W,G,SMD0402 | VISHAY ENTER TECHNO LOGY.INC | TNPW04028K66BEED |  |  |  |  |  |  |  |  |  |
|  |  |  |  | 218 | 218 | 61015JF00-017-G |  | RES,63.4 Ohm,+/-1%,1/10W,G,SMD0402 | KOA SPEER ELECTRONICS, INC. | RK73H1ETTP63R4F | 3 |  | PSIR10,PETR10,PERR10 |  |  |  |  |  |  |
|  |  |  |  | 219 | 219 | 61100PW00-017-G |  | RES,1.54KOhm,+/-0.1%,1/16W,G,SMD0402 | KOA SPEER ELECTRONICS, INC. | RN731ETTP1541B25 | 2 |  | PERR13,PERR15 |  |  |  |  |  |  |
|  |  |  |  |  | 219 | 61100PW00-024-G |  | RES,1.54KOhm,+/-0.1%,1/16W,G,SMD0402 | PANASONIC INDUSTRIAL CO.,LTD. | ERA2AEB1541X |  |  |  |  |  |  |  |  |  |
|  |  |  |  |  | 219 | 61100PW00-029-G |  | RES,1.54KOhm,+/-0.1%,1/16W,G,SMD0402 | VISHAY ENTER TECHNO LOGY.INC | TNPW04021K54BEED |  |  |  |  |  |  |  |  |  |
|  |  |  |  | 220 | 220 | 62011LT01-015-G |  | CAP,130pF,+/-5%,NPO(C0G),50V,G,SMD0402 | MURATA ELEC. NORTH AMERICA | GRM1555C1H131JA01D | 1 |  | PETC3 |  |  |  |  |  |  |
|  |  |  |  | 221 | 221 | 62011AM00-015-G |  | CAP,6.8nF,+/-10%,X7R,50V,G,SMD0402 | MURATA ELEC. NORTH AMERICA | GRM155R71H682K | 1 |  | PETC7 |  |  |  |  |  |  |
|  |  |  |  | 222 | 222 | 61011KY00-017-G |  | RES,3.83KOhm,+/-1%,1/16W,G,SMD0402 | KOA SPEER ELECTRONICS, INC. | RK73H1ETTP3831F | 1 |  | PETR2 |  |  |  |  |  |  |
|  |  |  |  |  | 222 | 61011KY00-029-G |  | RES,3.83KOhm,+/-1%,1/16W,G,SMD0402 | VISHAY ENTER TECHNO LOGY.INC | CRCW04023K83FKED |  |  |  |  |  |  |  |  |  |
|  |  |  |  | 223 | 223 | 611007000-017-G |  | RES,8.25KOhm,+/-0.1%,1/16W,G,SMD0402 | KOA SPEER ELECTRONICS, INC. | RN731ETTP8251B25 | 4 |  | PSIR8,PETR8,PSIR11,PETR11 |  |  |  |  |  |  |
|  |  |  |  | 224 | 224 | 61100AW00-017-G |  | RES,909 Ohm,+/-0.1%,1/16W,G,SMD0402 | KOA SPEER ELECTRONICS, INC. | RN731ETTP9090B25 | 2 |  | PETR13,PETR15 |  |  |  |  |  |  |
|  |  |  |  |  | 224 | 61100AW00-024-G |  | RES,909 Ohm,+/-0.1%,1/16W,G,SMD0402 | PANASONIC INDUSTRIAL CO.,LTD. | ERA2AEB9090X |  |  |  |  |  |  |  |  |  |
|  |  |  |  |  | 224 | 61100AW00-029-G |  | RES,909 Ohm,+/-0.1%,1/16W,G,SMD0402 | VISHAY ENTER TECHNO LOGY.INC | TNPW0402909RBEED |  |  |  |  |  |  |  |  |  |
|  |  |  |  | 225 | 225 | 620105U00-015-G |  | CAP,220pF,+/-10%,X7R,50V,G,SMD0402 | MURATA ELEC. NORTH AMERICA | GRM155R71H221K | 3 |  | PSTC14,PQPC14,PFRC14 |  |  |  |  |  |  |
|  |  |  |  |  | 225 | 620105U00-023-G |  | CAP,220pF,+/-10%,X7R,50V,G,SMD0402 | TAIYO ELECTRIC IND.CO.LTD | UMK105B7221KV-F |  |  |  |  |  |  |  |  |  |
|  |  |  |  |  | 225 | 620105U00-026-G |  | CAP,220pF,+/-10%,X7R,50V,G,SMD0402 | SAMSUNG SEMICONDUCTOR | CL05B221KB5NNNC |  |  |  |  |  |  |  |  |  |
|  |  |  |  | 226 | 226 | 63032PP00-088-G |  | IND,4.7uH@100KHz,+/-20%,5.5A,40mOhm,SHLD,G,SMD | COOPER BUSSMANN, INC. | HCM0703-4R7-R | 2 |  | PQPL2,PFRL2 |  |  |  |  |  |  |
|  |  |  |  | 227 | 227 | 61011R400-017-G |  | RES,34.8KOhm,+/-1%,1/16W,G,SMD0402 | KOA SPEER ELECTRONICS, INC. | RK73H1ETTP3482F | 1 |  | PFRR1 |  |  |  |  |  |  |
|  |  |  |  |  | 227 | 61011R400-024-G |  | RES,34.8KOhm,+/-1%,1/16W,G,SMD0402 | PANASONIC | ERJ2RKF3482X |  |  |  |  |  |  |  |  |  |
|  |  |  |  | 228 | 228 | 61100YB00-017-G |  | RES,2.94KOhm,+/-0.1%,1/16W,G,SMD0402 | KOA SPEER ELECTRONICS, INC. | RN731ETTP2941B25 | 1 |  | PFRR19 |  |  |  |  |  |  |
|  |  |  |  | 229 | 229 | 620133600-015-G |  | CAP,1nF,+/-5%,X7R,100V,G,SMD0805 | MURATA ELEC. NORTH AMERICA | GRM219R72A102JA01D | 1 |  | PHAC3 |  |  |  |  |  |  |
|  |  |  |  | 230 | 230 | 620135500-015-G |  | CAP,39nF,+/-10%,X7R,100V,G,SMD0805 | MURATA ELEC. NORTH AMERICA | GRM21BR72A393KA01L | 1 |  | PHAC18 |  |  |  |  |  |  |
|  |  |  |  | 231 | 231 | 52170KE00-086-G |  | TVS Diode,SMCJ64A,G,DO-214AB-2,SMD | LITTELFUSE FAR EAST PTE LTD | SMCJ64A | 1 |  | PHAD1 |  |  |  |  |  |  |
|  |  |  |  | 232 | 232 | 52030YE00-223-G |  | DIODE,Schottky,MBR5H100MFST1G,100V,5A,G,SO8FL-8,SMD | ON SEMICONDUCTOR CORP | MBR5H100MFST1G | 1 |  | PHAD2 |  |  |  |  |  |  |
|  |  |  |  | 233 | 233 | 52040EC00-237-G |  | DIODE,Zener,MMSZ5246B-7-F,16V,7.8mA,G,SOD123-2,SMD | DIODES INCORPORATION | MMSZ5246B-7-F | 1 |  | PHAD3 |  |  |  |  |  |  |
|  |  |  |  | 234 | 234 | 51031VY00-031-G |  | MOS N,PSMN4R8-100BSE,100V,120A,4.8m@10V,G,SOT404-3,SMD | NXP SEMICONDUCTORS | PSMN4R8-100BSE | 3 |  | PHAQ1,PHAQ2,PHAQ3 |  |  |  |  |  |  |
|  |  |  |  | 235 | 235 | 51020A000-031-G |  | TRANS P,PBHV9115T,150V,1A,G,SOT23-3,SMD | NXP SEMICONDUCTORS | PBHV9115T | 1 |  | PHAQ4 |  |  |  |  |  |  |
|  |  |  |  | 236 | 236 | 51032D100-237-G |  | MOS N,DMN10H220L-7,100V,1.6A,220m@10V,G,SOT-23-3,SMD | DIODES INCORPORATION | DMN10H220L-7 | 2 |  | PHAQ5,PHAQ6 |  |  |  |  |  |  |
|  |  |  |  | 237 | 237 | 610124C00-017-G |  | RES,57.6 Ohm,+/-1%,1/16W,G,SMD0402 | KOA SPEER ELECTRONICS, INC. | RK73H1ETTP57R6F | 4 |  | R1836,R1837,R1838,R1839 |  |  |  |  |  |  |
|  |  |  |  |  | 237 | 610124C00-024-G |  | RES,57.6 Ohm,+/-1%,1/16W,G,SMD0402 | PANASONIC | ERJ2RKF57R6X |  |  |  |  |  |  |  |  |  |
|  |  |  |  | 238 | 238 | 610602200-32D-G |  | RES,0.5mOhm,+/-1%,3W,G,SMD2512 | Thin Film Technology Corporation | CPA1225RR0005FW | 1 |  | PHAR1 |  |  |  |  |  |  |
|  |  |  |  | 239 | 239 | 61100DA00-017-G |  | RES,33KOhm,+/-0.1%,1/16W,G,SMD0402 | KOA SPEER ELECTRONICS, INC. | RN731ETTP3302B25 | 1 |  | PHAR2 |  |  |  |  |  |  |
|  |  |  |  | 240 | 240 | 61100QM00-017-G |  | RES,100KOhm,+/-0.1%,1/10W,G,SMD0603 | KOA SPEER ELECTRONICS, INC. | RN73H1JTTD1003B25 | 1 |  | PHAR5 |  |  |  |  |  |  |
|  |  |  |  | 241 | 241 | 610100R00-017-G |  | RES,3.74KOhm,+/-1%,1/10W,G,SMD0603 | KOA SPEER ELECTRONICS, INC. | RK73H1JTTD3741F | 1 |  | PHAR6 |  |  |  |  |  |  |
|  |  |  |  |  | 241 | 610100R00-024-G |  | RES,3.74KOhm,+/-1%,1/10W,G,SMD0603 | PANASONIC | ERJ3EKF3741V |  |  |  |  |  |  |  |  |  |
|  |  |  |  |  | 241 | 610100R00-029-G |  | RES,3.74KOhm,+/-1%,1/10W,G,SMD0603 | VISHAY | CRCW06033K74FKEB |  |  |  |  |  |  |  |  |  |
|  |  |  |  | 242 | 242 | 610107P00-017-G |  | RES,4.12KOhm,+/-1%,1/10W,G,SMD0603 | KOA SPEER ELECTRONICS, INC. | RK73H1JTTD4121F | 1 |  | PHAR7 |  |  |  |  |  |  |
|  |  |  |  | 243 | 243 | 61013GW00-017-G |  | RES,150KOhm,+/-1%,1/8W,G,SMD0805 | KOA SPEER ELECTRONICS, INC. | RK73H2ATTD1503F | 1 |  | PHAR13 |  |  |  |  |  |  |
|  |  |  |  | 244 | 244 | 610119P00-017-G |  | RES,5.11KOhm,+/-1%,1/16W,G,SMD0402 | KOA SPEER ELECTRONICS, INC. | RK73H1ETTP5111F | 1 |  | PHAR20 |  |  |  |  |  |  |
|  |  |  |  |  | 244 | 610119P00-024-G |  | RES,5.11KOhm,+/-1%,1/16W,G,SMD0402 | PANASONIC | ERJ2RKF5111X |  |  |  |  |  |  |  |  |  |
|  |  |  |  |  | 244 | 610119P00-029-G |  | RES,5.11KOhm,+/-1%,1/16W,G,SMD0402 | VISHAY | CRCW04025K11FKED |  |  |  |  |  |  |  |  |  |
|  |  |  |  | 245 | 245 | 61012Y700-017-G |  | RES,49.9KOhm,+/-1%,1/8W,G,SMD0805 | KOA SPEER ELECTRONICS, INC. | RK73H2ATTD4992F | 1 |  | PHAR78 |  |  |  |  |  |  |
|  |  |  |  | 246 | 246 | 32023RR00-183-G |  | IC,Power Controller,LM5066IPMHX/NOPB,G,HTSSOP-28,SMD | TEXAS INSTRUMENTS | LM5066IPMHX/NOPB | 1 |  | PHAU1 |  |  |  |  |  |  |
|  |  |  |  | 247 | 247 | 320245F00-173-G |  | IC,Power Controller,MAX6456UT29S+T,G,SOT-23-6,SMD | MAXIM INTEGRATED PRODUCTS, INC. | MAX6456UT29S+T | 1 |  | PHAU2 |  |  |  |  |  |  |
|  |  |  |  | 248 | 248 | 611006C00-017-G |  | RES,4.12KOhm,+/-0.1%,1/16W,G,SMD0402 | KOA SPEER ELECTRONICS, INC. | RN731ETTP4121B25 | 3 |  | PSIR13,PSIR15,PQPR19 |  |  |  |  |  |  |
|  |  |  |  |  | 248 | 611006C00-024-G |  | RES,4.12KOhm,+/-0.1%,1/16W,G,SMD0402 | PANASONIC INDUSTRIAL CO.,LTD. | ERA2AEB4121X |  |  |  |  |  |  |  |  |  |
|  |  |  |  |  | 248 | 611006C00-029-G |  | RES,4.12KOhm,+/-0.1%,1/16W,G,SMD0402 | VISHAY ENTER TECHNO LOGY.INC | TNPW04024K12BEED |  |  |  |  |  |  |  |  |  |
|  |  |  |  | 249 | 249 | 630328U00-088-G |  | IND,3.3uH@100KHz,+/-20%,6A,30mOhm,SHLD,G,SMD | COOPER BUSSMANN, INC. | HCM0703-3R3-R | 3 |  | PSTL2,PSLL2,PSDL2 |  |  |  |  |  |  |
|  |  |  |  | 250 | 250 | 61100KM01-017-G |  | RES,15KOhm,+/-0.1%,1/16W,G,SMD0402 | KOA SPEER ELECTRONICS, INC. | RN73H1ETTP1502B25 | 1 |  | PSDR19 |  |  |  |  |  |  |
|  |  |  |  |  | 250 | ERA2AEB1502X |  | RES,15KOhm,+/-0.1%,1/16W,G,SMD0402 | PANASONIC INDUSTRIAL CO.,LTD. | ERA2AEB1502X |  |  |  |  |  |  |  |  |  |
|  |  |  |  |  | 250 | MCS0402MD1502BE000 |  | RES,15KOhm,+/-0.1%,1/16W,G,SMD0402 | VISHAY ENTER TECHNO LOGY.INC | MCS0402MD1502BE000 |  |  |  |  |  |  |  |  |  |
|  |  |  |  | 251 | 251 | 63032A900-088-G |  | IND,1.5uH@100KHz,+/-20%,9A,15mOhm,SHLD,G,SMD | COOPER BUSSMANN, INC. | HCM0703-1R5-R | 2 |  | PSIL1,PSEL2 |  |  |  |  |  |  |
|  |  |  |  | 252 | 252 | 61100V400-017-G |  | RES,13.7KOhm,+/-0.1%,1/16W,G,SMD0402 | KOA SPEER ELECTRONICS, INC. | RN731ETTP1372B25 | 1 |  | PSER19 |  |  |  |  |  |  |
|  |  |  |  |  | 252 | 61100V400-024-G |  | RES,13.7KOhm,+/-0.1%,1/16W,G,SMD0402 | PANASONIC INDUSTRIAL CO.,LTD. | ERA2AEB1372X |  |  |  |  |  |  |  |  |  |
|  |  |  |  |  | 252 | 61100V400-029-G |  | RES,13.7KOhm,+/-0.1%,1/16W,G,SMD0402 | VISHAY ENTER TECHNO LOGY.INC | TNPW040213K7BEED |  |  |  |  |  |  |  |  |  |
|  |  |  |  | 253 | 253 | 61100Y900-017-G |  | RES,11.8KOhm,+/-0.1%,1/16W,G,SMD0402 | KOA SPEER ELECTRONICS, INC. | RN731ETTP1182B25 | 1 |  | PSFR19 |  |  |  |  |  |  |
|  |  |  |  |  | 253 | 61100Y900-024-G |  | RES,11.8KOhm,+/-0.1%,1/16W,G,SMD0402 | PANASONIC INDUSTRIAL CO.,LTD. | ERA2AEB1182X |  |  |  |  |  |  |  |  |  |
|  |  |  |  |  | 253 | 61100Y900-029-G |  | RES,11.8KOhm,+/-0.1%,1/16W,G,SMD0402 | VISHAY ENTER TECHNO LOGY.INC | TNPW040211K8BEED |  |  |  |  |  |  |  |  |  |
|  |  |  |  | 254 | 254 | 62011LY01-015-G |  | CAP,160pF,+/-5%,NPO(C0G),50V,G,SMD0402 | MURATA ELEC. NORTH AMERICA | GRM1555C1H161JA01D | 1 |  | PSIC3 |  |  |  |  |  |  |
|  |  |  |  | 255 | 255 | 61011MA00-017-G |  | RES,3.32KOhm,+/-1%,1/16W,G,SMD0402 | KOA SPEER ELECTRONICS, INC. | RK73H1ETTP3321F | 1 |  | PSIR2 |  |  |  |  |  |  |
|  |  |  |  |  | 255 | 61011MA00-024-G |  | RES,3.32KOhm,+/-1%,1/16W,G,SMD0402 | PANASONIC | ERJ2RKF3321X |  |  |  |  |  |  |  |  |  |
|  |  |  |  |  | 255 | 61011MA00-029-G |  | RES,3.32KOhm,+/-1%,1/16W,G,SMD0402 | VISHAY | CRCW04023K32FKED |  |  |  |  |  |  |  |  |  |
|  |  |  |  | 256 | 256 | 61100DF00-017-G |  | RES,6.34KOhm,+/-0.1%,1/16W,G,SMD0402 | KOA SPEER ELECTRONICS, INC. | RN731ETTP6341B25 | 1 |  | PSLR19 |  |  |  |  |  |  |
|  |  |  |  |  | 256 | 61100DF00-024-G |  | RES,6.34KOhm,+/-0.1%,1/16W,G,SMD0402 | PANASONIC INDUSTRIAL CO.,LTD. | ERA2AEB6341X |  |  |  |  |  |  |  |  |  |
|  |  |  |  |  | 256 | 61100DF00-029-G |  | RES,6.34KOhm,+/-0.1%,1/16W,G,SMD0402 | VISHAY ENTER TECHNO LOGY.INC | TNPW04026K34BEED |  |  |  |  |  |  |  |  |  |
|  |  |  |  | 257 | 257 | 62013BS00-015-G |  | CAP,3nF,+/-10%,X7R,50V,G,SMD0402 | MURATA ELEC. NORTH AMERICA | GRM155R71H302KA01D | 1 |  | PSPC10 |  |  |  |  |  |  |
|  |  |  |  | 258 | 258 | 62120BA00-022-G |  | SPEA,CAP,180uF,+/-20%,16V,105C,G,SMD6.3*5.9,ESR<=22mOhm | SANYO ELECTRIC CO., LTD. | 16SVPF180M | 1 |  | PSRCE1 |  |  |  |  |  |  |
|  |  |  |  | 259 | 259 | 62012T500-015-G |  | CAP,22uF,+/-20%,X7S,25V,G,SMD1206 | MURATA ELEC. NORTH AMERICA | GRM31CC71E226ME11L | 12 |  | PSRC4,PSUC5,PSRC5,PSUC6,PSRC6,PSUC7,PSUC8,PSUC9,PSUC10,PSRC3001,PSRC3002,PSRC3005 |  |  |  |  |  |  |
|  |  |  |  | 260 | 260 | 62013BQ00-015-G |  | CAP,3.6nF,+/-10%,X7R,50V,G,SMD0402 | MURATA ELEC. NORTH AMERICA | GRM155R71H362KA01D | 1 |  | PSRC7 |  |  |  |  |  |  |
|  |  |  |  | 261 | 261 | 63033PG00-15A-G |  | IND,22nH@100KHz,+/-15%,22A,249.55uOhm,SHLD,G,SMD | The Inter-Technical Group, Inc. | SLC1615A-R022LHF | 1 |  | PSRL1 |  |  |  |  |  |  |
|  |  |  |  | 262 | 262 | 63034GW00-088-G |  | IND,680nH@100KHz,+/-20%,34A,1.33mOhm,SHLD,G,SMD | COOPER BUSSMANN, INC. | HCM1305-R68-R | 1 |  | PSRL2 |  |  |  |  |  |  |
|  |  |  |  | 263 | 263 | 61011MN00-017-G |  | RES,976 Ohm,+/-1%,1/16W,G,SMD0402 | KOA SPEER ELECTRONICS, INC. | RK73H1ETTP9760F | 1 |  | PSRR11 |  |  |  |  |  |  |
|  |  |  |  | 264 | 264 | 61100P800-017-G |  | RES,8.45KOhm,+/-0.1%,1/16W,G,SMD0402 | KOA SPEER ELECTRONICS, INC. | RN731ETTP8451B25 | 1 |  | PSRR12 |  |  |  |  |  |  |
|  |  |  |  |  | 264 | 61100P800-024-G |  | RES,8.45KOhm,+/-0.1%,1/16W,G,SMD0402 | PANASONIC INDUSTRIAL CO.,LTD. | ERA2AEB8451X |  |  |  |  |  |  |  |  |  |
|  |  |  |  |  | 264 | 61100P800-029-G |  | RES,8.45KOhm,+/-0.1%,1/16W,G,SMD0402 | VISHAY ENTER TECHNO LOGY.INC | TNPW04028K45BEED |  |  |  |  |  |  |  |  |  |
|  |  |  |  | 265 | 265 | 610114A00-017-G |  | RES,24.9KOhm,+/-1%,1/16W,G,SMD0402 | KOA SPEER ELECTRONICS, INC. | RK73H1ETTP2492F | 1 |  | PSRR13 |  |  |  |  |  |  |
|  |  |  |  |  | 265 | 610114A00-024-G |  | RES,24.9KOhm,+/-1%,1/16W,G,SMD0402 | PANASONIC | ERJ2RKF2492X |  |  |  |  |  |  |  |  |  |
|  |  |  |  |  | 265 | 610114A00-029-G |  | RES,24.9KOhm,+/-1%,1/16W,G,SMD0402 | VISHAY | CRCW040224K9FKED |  |  |  |  |  |  |  |  |  |
|  |  |  |  | 266 | 266 | 61100PM00-017-G |  | RES,453 Ohm,+/-0.1%,1/16W,G,SMD0402 | KOA SPEER ELECTRONICS, INC. | RN731ETTP4530B25 | 1 |  | PSRR17 |  |  |  |  |  |  |
|  |  |  |  | 267 | 267 | 61011C300-017-G |  | RES,2.2 Ohm,+/-1%,1/16W,G,SMD0402 | KOA SPEER ELECTRONICS, INC. | RK73H1ETTP2R20F | 1 |  | PSRR3006 |  |  |  |  |  |  |
|  |  |  |  | 268 | 268 | 32013FK00-238-G |  | IC,Regulator,IR3846MTRPBF,ADJ,35A,G,PQFN-26,SMD | INTERNATIONAL RECTIFIER | IR3846MTRPBF | 1 |  | PSRU1 |  |  |  |  |  |  |
|  |  |  |  | 269 | 269 | 61100QA00-017-G |  | RES,16KOhm,+/-0.1%,1/16W,G,SMD0402 | KOA SPEER ELECTRONICS, INC. | RN731ETTP1602B25 | 1 |  | PSTR17 |  |  |  |  |  |  |
|  |  |  |  |  | 269 | 61100QA00-024-G |  | RES,16KOhm,+/-0.1%,1/16W,G,SMD0402 | PANASONIC INDUSTRIAL CO.,LTD. | ERA2AEB1602X |  |  |  |  |  |  |  |  |  |
|  |  |  |  |  | 269 | 61100QA00-029-G |  | RES,16KOhm,+/-0.1%,1/16W,G,SMD0402 | VISHAY ENTER TECHNO LOGY.INC | TNPW040216K0BEED |  |  |  |  |  |  |  |  |  |
|  |  |  |  | 270 | 270 | 61100J401-017-G |  | RES,1.78KOhm,+/-0.1%,1/16W,G,SMD0402 | KOA SPEER ELECTRONICS, INC. | RN73H1ETTP1781B25 | 1 |  | PSTR19 |  |  |  |  |  |  |
|  |  |  |  |  | 270 | 61100J400-024-G |  | RES,1.78KOhm,+/-0.1%,1/16W,G,SMD0402 | PANASONIC INDUSTRIAL CO.,LTD. | ERA2AEB1781X |  |  |  |  |  |  |  |  |  |
|  |  |  |  |  | 270 | MCS0402MD1781BE000 |  | RES,1.78KOhm,+/-0.1%,1/16W,G,SMD0402 | VISHAY ENTER TECHNO LOGY.INC | MCS0402MD1781BE000 |  |  |  |  |  |  |  |  |  |
|  |  |  |  | 271 | 271 | 730108L00-086-G |  | Fuse,Fast acting,500V,20A,G,SMD | LITTELFUSE FAR EAST PTE LTD | 0505020.MXP | 1 |  | PSUFS1 |  |  |  |  |  |  |
|  |  |  |  | 272 | 272 | 51030CQ00-185-G |  | MOS N,2N7002,60V,115mA,7.5ohm@5V,G,SOT23-3,SMD | FAIRCHILD SEMICONDUCTOR CORP | 2N7002 | 3 |  | PSUQ1,Q2,Q6 |  |  |  |  |  |  |
|  |  |  |  |  | 272 | 510301N00-223-G |  | MOS N,2N7002LT1G,60V,0.115A,7.5ohm@5V,G,SOT23-3,SMD | ON SEMICONDUCTOR CORP | 2N7002LT1G |  |  |  |  |  |  |  |  |  |
|  |  |  |  | 273 | 273 | 610115R00-017-G |  | RES,15KOhm,+/-1%,1/16W,G,SMD0402 | KOA SPEER ELECTRONICS, INC. | RK73H1ETTP1502F | 1 |  | PSUR1 |  |  |  |  |  |  |
|  |  |  |  |  | 273 | 610115R00-024-G |  | RES,15KOhm,+/-1%,1/16W,G,SMD0402 | PANASONIC INDUSTRIAL CO.,LTD. | ERJ2RKF1502X |  |  |  |  |  |  |  |  |  |
|  |  |  |  |  | 273 | 610115R00-029-G |  | RES,15KOhm,+/-1%,1/16W,G,SMD040 | VISHAY ENTER TECHNO LOGY.INC | CRCW040215K0FKED |  |  |  |  |  |  |  |  |  |
|  |  |  |  | 274 | 274 | 880302300-065-G |  | Converter,input 40V~60V,600W,G,Q54SJ12050NNDH | DELTA ELECTRONICS INDUSTRIAL CO.,LTD | Q54SJ12050NNDH | 1 |  | PSUU1 |  |  |  |  |  |  |
|  |  |  |  | 275 | 275 | 510507500-185-G |  | MOS N/P,FDC6327C,20V,2.7/1.9A,80m/170m@4.5V,G,SuperSOT-6,SMD | FAIRCHILD SEMICONDUCTOR CORP | FDC6327C | 1 |  | QN1 |  |  |  |  |  |  |
|  |  |  |  | 276 | 276 | 510503B00-223-G |  | MOS N/N,NTZD3154NT1G,20V,0.54A,550m24.5V,G,SOT563-6,SMD | ON SEMICONDUCTOR CORP | NTZD3154NT1G | 1 |  | QN2 |  |  |  |  |  |  |
|  |  |  |  | 277 | 277 | 51030QP00-237-G |  | MOS N,BSS138W-7-F,50V,0.2A,3.5ohm@10V,G,SOT323-3,SMD | DIODES INCORPORATION | BSS138W-7-F | 44 |  | Q1,Q9,Q10,Q11,Q13,Q14,Q24,Q25,Q26,Q27,Q28,Q29,Q30,Q31,Q32,Q33,Q34,Q35,Q36,Q37,Q38,Q39,Q40,Q41,Q42,Q43,Q44,Q45,Q46,Q47,Q48,Q49,Q50,Q51,Q52,Q53,Q54,Q55,Q56,Q57,Q58,Q59,Q60,Q93 |  |  |  |  |  |  |
|  |  |  |  | 278 | 278 | 510406000-185-G |  | MOS P,FDD6685,30V,11A,30m@4.5V,G,TO252-3,SMD | FAIRCHILD SEMICONDUCTOR CORP | FDD6685 | 2 |  | Q5,Q7 |  |  |  |  |  |  |
|  |  |  |  | 279 | 279 | 510501900-237-G |  | MOS N/N,2N7002DW-7-F,60V,0.115A,7.5ohm@5V,G,SOT363-6,SMD | DIODES INCORPORATION | 2N7002DW-7-F | 1 |  | Q12 |  |  |  |  |  |  |
|  |  |  |  | 280 | 280 | 610130300-017-G |  | RES,60.4 Ohm,+/-1%,1/20W,G,SMD0201 | KOA SPEER ELECTRONICS, INC. | RK73H1HTTC60R4F | 2 |  | R1769,R1770 |  |  |  |  |  |  |
|  |  |  |  |  | 280 | 610130300-024-G |  | RES,60.4 Ohm,+/-1%,1/20W,G,SMD0201 | PANASONIC INDUSTRIAL CO.,LTD. | ERJ1GNF60R4C |  |  |  |  |  |  |  |  |  |
|  |  |  |  |  | 280 | CRCW020160R4FKED |  | RES,60.4 Ohm,+/-1%,1/20W,G,SMD0201 | VISHAY ENTER TECHNO LOGY.INC | CRCW020160R4FKED |  |  |  |  |  |  |  |  |  |
|  |  |  |  | 281 | 281 | 61100QE00-017-G |  | RES,240 Ohm,+/-0.1%,1/16W,G,SMD0402 | KOA SPEER ELECTRONICS, INC. | RN731ETTP2400B25 | 4 |  | R3,R8,R365,R370 |  |  |  |  |  |  |
|  |  |  |  | 282 | 282 | 610100T00-017-G |  | RES,1KOhm,+/-5%,1/16W,G,SMD0402 | KOA SPEER ELECTRONICS, INC. | RK73B1ETTP102J | 107 |  | R4,R5,R9,R10,R103,R129,R130,R131,R150,R151,R154,R171,R172,R175,R192,R193,R195,R213,R214,R215,R234,R235,R236,R255,R256,R259,R276,R277,R279,R318,R319,R366,R367,R371,R372,R455,R458,R484,R485,R486,R505,R506,R509,R526,R527,R530,R547,R548,R550,R568,R569,R570,R589,R590,R591,R611,R612,R615,R631,R632,R634,R704,R705,R706,R711,R715,R735,R736,R1072,R1080,R1232,R1340,R1341,R1350,R1351,R1352,R1353,R1354,R1355,R1356,R1357,R1358,R1359,R1361,R1363,R1364,R1365,R1366,R1367,R1377,R1378,R1379,R1380,R1381,R1382,R1383,R1384,R1385,R1386,R1387,R1388,R1389,R1390,R1391,R1392,R1746,R1775 |  |  |  |  |  |  |
|  |  |  |  |  | 282 | 610100T00-024-G |  | RES,1KOhm,+/-5%,1/16W,G,SMD0402 | PANASONIC INDUSTRIAL CO.,LTD. | ERJ2GEJ102X |  |  |  |  |  |  |  |  |  |
|  |  |  |  | 283 | 283 | 61100Y400-017-G |  | RES,169 Ohm,+/-0.1%,1/16W,G,SMD0402 | KOA SPEER ELECTRONICS, INC. | RN731ETTP1690B25 | 6 |  | R11,R12,R13,R373,R374,R375 |  |  |  |  |  |  |
|  |  |  |  | 284 | 284 | 610102700-017-G |  | RES,49.9 Ohm,+/-1%,1/16W,G,SMD0402 | KOA SPEER ELECTRONICS, INC. | RK73H1ETTP49R9F | 204 |  | R16,R17,R18,R19,R20,R21,R24,R25,R33,R34,R35,R36,R37,R46,R47,R48,R49,R50,R51,R65,R66,R69,R76,R94,R95,R99,R100,R101,R104,R105,R106,R107,R110,R111,R112,R113,R114,R115,R117,R121,R138,R139,R140,R146,R147,R148,R155,R160,R161,R164,R166,R169,R177,R180,R182,R186,R187,R189,R197,R198,R203,R206,R207,R208,R222,R223,R224,R230,R231,R232,R240,R244,R245,R248,R250,R253,R261,R264,R266,R270,R271,R273,R281,R282,R287,R291,R292,R293,R376,R379,R380,R381,R382,R383,R386,R387,R391,R392,R395,R396,R397,R398,R400,R405,R406,R407,R408,R409,R410,R421,R422,R423,R424,R425,R426,R427,R432,R435,R436,R445,R446,R449,R453,R456,R457,R459,R460,R461,R493,R494,R495,R501,R502,R503,R510,R515,R516,R519,R521,R524,R533,R535,R537,R541,R542,R544,R552,R553,R558,R561,R562,R563,R577,R578,R579,R585,R586,R587,R594,R599,R600,R603,R605,R608,R610,R617,R621,R625,R626,R628,R636,R637,R642,R645,R646,R647,R1346,R1348,R1349,R1368,R1371,R1374,R1396,R1397,R1401,R1402,R1408,R1409,R1410,R1411,R1419,R1420,R1421,R1429,R1430,R1431,R1591,R1811,R1822,R1827,R1828,R1829,R1830,R1831 |  |  |  |  |  |  |
|  |  |  |  |  | 284 | 610102700-029-G |  | RES,49.9 Ohm,+/-1%,1/16W,G,SMD0402 | VISHAY ENTER TECHNO LOGY.INC | CRCW040249R9FKED |  |  |  |  |  |  |  |  |  |
|  |  |  |  |  | 284 | 610102700-024-G |  | RES,49.9 Ohm,+/-1%,1/16W,G,SMD0402 | PANASONIC INDUSTRIAL CO.,LTD. | ERJ2RKF49R9X |  |  |  |  |  |  |  |  |  |
|  |  |  |  | 285 | 285 | 61010KJ00-017-G |  | RES,3.3KOhm,+/-5%,1/16W,G,SMD0402 | KOA SPEER ELECTRONICS, INC. | RK73B1ETTP332J | 80 |  | R22,R23,R26,R32,R38,R39,R41,R42,R43,R44,R45,R52,R68,R88,R89,R299,R300,R301,R302,R342,R384,R385,R388,R389,R390,R394,R399,R401,R403,R404,R411,R412,R413,R441,R442,R465,R466,R468,R469,R470,R472,R475,R476,R954,R1029,R1031,R1032,R1033,R1034,R1035,R1041,R1042,R1043,R1044,R1047,R1048,R1050,R1051,R1054,R1055,R1059,R1060,R1063,R1064,R1067,R1068,R1127,R1128,R1139,R1141,R1225,R1227,R1229,R1234,R1239,R1336,R1337,R1524,R1525,R1823 |  |  |  |  |  |  |
|  |  |  |  |  | 285 | 61010KJ00-024-G |  | RES,3.3KOhm,+/-5%,1/16W,G,SMD0402 | PANASONIC INDUSTRIAL CO.,LTD. | ERJ2GEJ332X |  |  |  |  |  |  |  |  |  |
|  |  |  |  | 286 | 286 | 610115E00-017-G |  | RES,1.2KOhm,+/-5%,1/16W,G,SMD0402 | KOA SPEER ELECTRONICS, INC. | RK73B1ETTP122J | 12 |  | R27,R28,R54,R55,R56,R57,R58,R59,R417,R418,R419,R420 |  |  |  |  |  |  |
|  |  |  |  |  | 286 | 610115E00-024-G |  | RES,1.2KOhm,+/-5%,1/16W,G,SMD0402 | PANASONIC INDUSTRIAL CO.,LTD. | ERJ2GEJ122X |  |  |  |  |  |  |  |  |  |
|  |  |  |  | 287 | 287 | 61100V600-017-G |  | RES,200 Ohm,+/-0.1%,1/16W,G,SMD0402 | KOA SPEER ELECTRONICS, INC. | RN731ETTP2000B25 | 6 |  | R31,R40,R53,R393,R402,R416 |  |  |  |  |  |  |
|  |  |  |  | 288 | 288 | 610115T00-017-G |  | RES,40.2KOhm,+/-1%,1/16W,G,SMD0402 | KOA SPEER ELECTRONICS, INC. | RK73H1ETTP4022F | 1 |  | R78 |  |  |  |  |  |  |
|  |  |  |  |  | 288 | 610115T00-029-G |  | RES,40.2KOhm,+/-1%,1/16W,G,SMD0402 | VISHAY ENTER TECHNO LOGY.INC | CRCW040240K2FKEDC |  |  |  |  |  |  |  |  |  |
|  |  |  |  | 289 | 289 | 610112W00-017-G |  | RES,2KOhm,+/-5%,1/16W,G,SMD0402 | KOA SPEER ELECTRONICS, INC. | RK73B1ETTP202J | 7 |  | R96,R97,R98,R447,R448,R452,R454 |  |  |  |  |  |  |
|  |  |  |  |  | 289 | 610112W00-024-G |  | RES,2KOhm,+/-5%,1/16W,G,SMD0402 | PANASONIC INDUSTRIAL CO.,LTD. | ERJ2GEJ202X |  |  |  |  |  |  |  |  |  |
|  |  |  |  | 290 | 290 | 61010DL01-017-G |  | RES,0 Ohm,+/-5%,1/8W,G,SMD0805 | KOA SPEER ELECTRONICS, INC. | RK73Z2ATTD | 6 |  | R108,R109,R463,R464,R700,R701 |  |  |  |  |  |  |
|  |  |  |  |  | 290 | 61010DL00-024-G |  | RES,0 Ohm,+/-5%,1/8W,G,SMD0805 | PANASONIC INDUSTRIAL CO.,LTD. | ERJ6GEY0R00V |  |  |  |  |  |  |  |  |  |
|  |  |  |  | 291 | 291 | 610102E00-017-G |  | RES,100 Ohm,+/-5%,1/16W,G,SMD0402 | KOA SPEER ELECTRONICS, INC. | RK73B1ETTP101J | 64 |  | R132,R137,R141,R143,R152,R158,R162,R167,R173,R179,R183,R188,R194,R200,R204,R209,R216,R221,R225,R227,R237,R239,R246,R251,R257,R263,R267,R272,R278,R284,R288,R290,R487,R492,R496,R498,R507,R513,R517,R522,R528,R531,R538,R543,R549,R555,R559,R564,R571,R576,R580,R582,R592,R597,R601,R606,R613,R620,R622,R627,R633,R639,R643,R648 |  |  |  |  |  |  |
|  |  |  |  |  | 291 | 610102E00-029-G |  | RES,100 Ohm,+/-5%,1/16W,G,SMD0402 | VISHAY ENTER TECHNO LOGY.INC | CRCW0402100RJNED |  |  |  |  |  |  |  |  |  |
|  |  |  |  | 292 | 292 | 610107B00-017-G |  | RES,4.7KOhm,+/-5%,1/16W,G,SMD0402 | KOA SPEER ELECTRONICS, INC. | RK73B1ETTP472J | 7 |  | R297,R298,R304,R1069,R1070,R1342,R1343 |  |  |  |  |  |  |
|  |  |  |  |  | 292 | 610107B00-024-G |  | RES,4.7KOhm,+/-5%,1/16W,G,SMD0402 | PANASONIC INDUSTRIAL CO.,LTD. | ERJ2GEJ472X |  |  |  |  |  |  |  |  |  |
|  |  |  |  |  | 292 | 610107B00-029-G |  | RES,4.7KOhm,+/-5%,1/16W,G,SMD0402 | VISHAY ENTER TECHNO LOGY.INC | CRCW04024K70JNED |  |  |  |  |  |  |  |  |  |
|  |  |  |  | 293 | 293 | 610112U00-017-G |  | RES,499 Ohm,+/-1%,1/16W,G,SMD0402 | KOA SPEER ELECTRONICS, INC. | RK73H1ETTP4990F | 1 |  | R307 |  |  |  |  |  |  |
|  |  |  |  |  | 293 | 610112U00-024-G |  | RES,499 Ohm,+/-1%,1/16W,G,SMD0402 | PANASONIC INDUSTRIAL CO.,LTD. | ERJ2RKF4990X |  |  |  |  |  |  |  |  |  |
|  |  |  |  | 294 | 294 | 610107C00-017-G |  | RES,10KOhm,+/-5%,1/16W,G,SMD0402 | KOA SPEER ELECTRONICS, INC. | RK73B1ETTP103J | 2 |  | R310,R990 |  |  |  |  |  |  |
|  |  |  |  |  | 294 | 610107C00-024-G |  | RES,10KOhm,+/-5%,1/16W,G,SMD0402 | PANASONIC INDUSTRIAL CO.,LTD. | ERJ2GEJ103X |  |  |  |  |  |  |  |  |  |
|  |  |  |  |  | 294 | 610107C00-029-G |  | RES,10KOhm,+/-5%,1/16W,G,SMD0402 | VISHAY ENTER TECHNO LOGY.INC | CRCW040210K0JNED |  |  |  |  |  |  |  |  |  |
|  |  |  |  | 295 | 295 | 61011MW00-017-G |  | RES,31.6KOhm,+/-1%,1/16W,G,SMD0402 | KOA SPEER ELECTRONICS, INC. | RK73H1ETTP3162F | 1 |  | R328 |  |  |  |  |  |  |
|  |  |  |  | 296 | 296 | 610118G00-017-G |  | RES,90.9KOhm,+/-1%,1/16W,G,SMD0402 | KOA SPEER ELECTRONICS, INC. | RK73H1ETTP9092F | 1 |  | R329 |  |  |  |  |  |  |
|  |  |  |  |  | 296 | 610118G00-024-G |  | RES,90.9KOhm,+/-1%,1/16W,G,SMD0402 | PANASONIC INDUSTRIAL CO.,LTD. | ERJ2RKF9092X |  |  |  |  |  |  |  |  |  |
|  |  |  |  | 297 | 297 | 610116J00-017-G |  | RES,1.21KOhm,+/-1%,1/16W,G,SMD0402 | KOA SPEER ELECTRONICS, INC. | RK73H1ETTP1211F | 13 |  | R332,R333,R334,R335,R336,R337,R338,R339,R340,R341,R343,R344,R345 |  |  |  |  |  |  |
|  |  |  |  |  | 297 | 610116J00-024-G |  | RES,1.21KOhm,+/-1%,1/16W,G,SMD0402 | PANASONIC INDUSTRIAL CO.,LTD. | ERJ2RKF1211X |  |  |  |  |  |  |  |  |  |
|  |  |  |  |  | 297 | 610116J00-029-G |  | RES,1.21KOhm,+/-1%,1/16W,G,SMD0402 | VISHAY ENTER TECHNO LOGY.INC | CRCW04021K21FKED |  |  |  |  |  |  |  |  |  |
|  |  |  |  | 298 | 298 | 610114W00-017-G |  | RES,3.01KOhm,+/-1%,1/16W,G,SMD0402 | KOA SPEER ELECTRONICS, INC. | RK73H1ETTP3011F | 1 |  | R346 |  |  |  |  |  |  |
|  |  |  |  |  | 298 | 610114W00-029-G |  | RES,3.01KOhm,+/-1%,1/16W,G,SMD0402 | VISHAY ENTER TECHNO LOGY.INC | CRCW04023K01FKED |  |  |  |  |  |  |  |  |  |
|  |  |  |  | 299 | 299 | 61010L600-017-G |  | RES,11KOhm,+/-1%,1/16W,G,SMD0402 | KOA SPEER ELECTRONICS, INC. | RK73H1ETTP1102F | 1 |  | R349 |  |  |  |  |  |  |
|  |  |  |  |  | 299 | 61010L600-024-G |  | RES,11KOhm,+/-1%,1/16W,G,SMD0402 | PANASONIC INDUSTRIAL CO.,LTD. | ERJ2RKF1102X |  |  |  |  |  |  |  |  |  |
|  |  |  |  |  | 299 | 61010L600-029-G |  | RES,11KOhm,+/-1%,1/16W,G,SMD0402 | VISHAY ENTER TECHNO LOGY.INC | CRCW040211K0FKEDC |  |  |  |  |  |  |  |  |  |
|  |  |  |  | 300 | 300 | 61011KS00-017-G |  | RES,47KOhm,+/-1%,1/16W,G,SMD0402 | KOA SPEER ELECTRONICS, INC. | RK73H1ETTP4702F | 2 |  | R652,R658 |  |  |  |  |  |  |
|  |  |  |  |  | 300 | 61011KS00-029-G |  | RES,47KOhm,+/-1%,1/16W,G,SMD0402 | VISHAY ENTER TECHNO LOGY.INC | CRCW040247K0FKED |  |  |  |  |  |  |  |  |  |
|  |  |  |  | 301 | 301 | 61010FL00-017-G |  | RES,2.2KOhm,+/-5%,1/16W,G,SMD0402 | KOA SPEER ELECTRONICS, INC. | RK73B1ETTP222J | 6 |  | R664,R665,R666,R673,R1020,R1021 |  |  |  |  |  |  |
|  |  |  |  |  | 301 | 61010FL00-029-G |  | RES,2.2KOhm,+/-5%,1/16W,G,SMD0402 | VISHAY ENTER TECHNO LOGY.INC | CRCW04022K20JNED |  |  |  |  |  |  |  |  |  |
|  |  |  |  |  | 301 | 61010FL00-024-G |  | RES,2.2KOhm,+/-5%,1/16W,G,SMD0402 | PANASONIC INDUSTRIAL CO.,LTD. | ERJ2GEJ222X |  |  |  |  |  |  |  |  |  |
|  |  |  |  | 302 | 302 | 610112L00-017-G |  | RES,1.24KOhm,+/-1%,1/16W,G,SMD0402 | KOA SPEER ELECTRONICS, INC. | RK73H1ETTP1241F | 2 |  | R690,R753 |  |  |  |  |  |  |
|  |  |  |  |  | 302 | 610112L00-029-G |  | RES,1.24KOhm,+/-1%,1/16W,G,SMD0402 | VISHAY ENTER TECHNO LOGY.INC | CRCW04021K24FKED |  |  |  |  |  |  |  |  |  |
|  |  |  |  |  | 302 | 610112L00-024-G |  | RES,1.24KOhm,+/-1%,1/16W,G,SMD0402 | PANASONIC INDUSTRIAL CO.,LTD. | ERJ2RKF1241X |  |  |  |  |  |  |  |  |  |
|  |  |  |  | 303 | 303 | 610104E00-017-G |  | RES,470 Ohm,+/-1%,1/10W,G,SMD0603 | KOA SPEER ELECTRONICS, INC. | RK73H1JTTD4700F | 1 |  | R699 |  |  |  |  |  |  |
|  |  |  |  |  | 303 | 610104E00-024-G |  | RES,470 Ohm,+/-1%,1/10W,G,SMD0603 | PANASONIC INDUSTRIAL CO.,LTD. | ERJ3EKF4700V |  |  |  |  |  |  |  |  |  |
|  |  |  |  | 304 | 304 | 61013W100-017-G |  | RES,20mOhm,+/-1%,1/5W,G,SMD0603 | KOA SPEER ELECTRONICS, INC. | UR73D1JTTD20L0F | 1 |  | R702 |  |  |  |  |  |  |
|  |  |  |  | 305 | 305 | 61011H500-017-G |  | RES,22 Ohm,+/-1%,1/16W,G,SMD0402 | KOA SPEER ELECTRONICS, INC. | RK73H1ETTP22R0F | 19 |  | R725,R727,R729,R730,R815,R816,R818,R1012,R1015,R1161,R1163,R1171,R1173,R1183,R1189,R1196,R1202,R1206,R1209 |  |  |  |  |  |  |
|  |  |  |  |  | 305 | 61011H500-024-G |  | RES,22 Ohm,+/-1%,1/16W,G,SMD0402 | PANASONIC INDUSTRIAL CO.,LTD. | ERJ2RKF22R0X |  |  |  |  |  |  |  |  |  |
|  |  |  |  | 306 | 306 | 610112B00-017-G |  | RES,3.4KOhm,+/-1%,1/16W,G,SMD0402 | KOA SPEER ELECTRONICS, INC. | RK73H1ETTP3401F | 2 |  | R733,R734 |  |  |  |  |  |  |
|  |  |  |  | 307 | 307 | 61011B000-017-G |  | RES,1.5KOhm,+/-1%,1/16W,G,SMD0402 | KOA SPEER ELECTRONICS, INC. | RK73H1ETTP1501F | 2 |  | R738,R1111 |  |  |  |  |  |  |
|  |  |  |  |  | 307 | 61011B000-024-G |  | RES,1.5KOhm,+/-1%,1/16W,G,SMD0402 | PANASONIC INDUSTRIAL CO.,LTD. | ERJ2RKF1501X |  |  |  |  |  |  |  |  |  |
|  |  |  |  | 308 | 308 | 610101V00-017-G |  | RES,22 Ohm,+/-5%,1/16W,G,SMD0402 | KOA SPEER ELECTRONICS, INC. | RK73B1ETTP220J | 23 |  | R79,R80,R81,R82,R83,R1806,R739,R740,R741,R742,R743,R749,R933,R934,R935,R936,R937,R938,R993,R994,R995,R996,R997 |  |  |  |  |  |  |
|  |  |  |  |  | 308 | 610101V00-024-G |  | RES,22 Ohm,+/-5%,1/16W,G,SMD0402 | PANASONIC INDUSTRIAL CO.,LTD. | ERJ2GEJ220X |  |  |  |  |  |  |  |  |  |
|  |  |  |  | 309 | 309 | 61100H601-017-G |  | RES,2KOhm,+/-0.5%,1/16W,G,SMD0402 | KOA SPEER ELECTRONICS, INC. | RN731ETTP2001D25 | 1 |  | R751 |  |  |  |  |  |  |
|  |  |  |  | 310 | 310 | 61011T800-017-G |  | RES,240 Ohm,+/-1%,1/16W,G,SMD0402 | KOA SPEER ELECTRONICS, INC. | RK73H1ETTP2400F | 1 |  | R789 |  |  |  |  |  |  |
|  |  |  |  | 311 | 311 | 61100BN00-017-G |  | RES,100KOhm,+/-1%,1/16W,G,SMD0402 | KOA SPEER ELECTRONICS, INC. | RN731ETTP1003F25 | 4 |  | R790,R1154,R1157,R1237 |  |  |  |  |  |  |
|  |  |  |  | 312 | 312 | 610115J00-017-G |  | RES,33 Ohm,+/-1%,1/16W,G,SMD0402 | KOA SPEER ELECTRONICS, INC. | RK73H1ETTP33R0F | 6 |  | R792,R793,R794,R796,R797,R799 |  |  |  |  |  |  |
|  |  |  |  |  | 312 | 610115J00-024-G |  | RES,33 Ohm,+/-1%,1/16W,G,SMD0402 | PANASONIC INDUSTRIAL CO.,LTD. | ERJ2RKF33R0X |  |  |  |  |  |  |  |  |  |
|  |  |  |  | 313 | 313 | 61011H100-017-G |  | RES,220 Ohm,+/-1%,1/16W,G,SMD0402 | KOA SPEER ELECTRONICS, INC. | RK73H1ETTP2200F | 7 |  | R831,R832,R833,R834,R1345,R1347,R1494 |  |  |  |  |  |  |
|  |  |  |  |  | 313 | 61011H100-024-G |  | RES,220 Ohm,+/-1%,1/16W,G,SMD0402 | PANASONIC INDUSTRIAL CO.,LTD. | ERJ2RKF2200X |  |  |  |  |  |  |  |  |  |
|  |  |  |  |  | 313 | 61011H100-029-G |  | RES,220 Ohm,+/-1%,1/16W,G,SMD0402 | VISHAY ENTER TECHNO LOGY.INC | CRCW0402220RFKEDC |  |  |  |  |  |  |  |  |  |
|  |  |  |  | 314 | 314 | 61011U901-017-G |  | RES,120Ohm,+/-1%,1/20W,G,SMD0201 | KOA SPEER ELECTRONICS, INC. | RK73H1HTTC1200F | 48 |  | R839,R840,R841,R842,R843,R844,R845,R846,R847,R848,R849,R850,R851,R852,R853,R854,R855,R856,R857,R858,R859,R860,R861,R862,R867,R868,R869,R870,R871,R872,R873,R874,R875,R876,R877,R878,R879,R880,R881,R882,R883,R884,R885,R887,R888,R889,R890,R891 |  |  |  |  |  |  |
|  |  |  |  | 315 | 315 | 61011KH00-017-G |  | RES,240 Ohm,+/-5%,1/16W,G,SMD0402 | KOA SPEER ELECTRONICS, INC. | RK73B1ETTP241J | 1 |  | R886 |  |  |  |  |  |  |
|  |  |  |  |  | 315 | 61011KH00-024-G |  | RES,240 Ohm,+/-5%,1/16W,G,SMD0402 | PANASONIC INDUSTRIAL CO.,LTD. | ERJ2GEJ241X |  |  |  |  |  |  |  |  |  |
|  |  |  |  | 316 | 316 | 610102600-017-G |  | RES,56 Ohm,+/-1%,1/16W,G,SMD0402 | KOA SPEER ELECTRONICS, INC. | RK73H1ETTP56R0F | 3 |  | R925,R927,R929 |  |  |  |  |  |  |
|  |  |  |  |  | 316 | 610102600-024-G |  | RES,56 Ohm,+/-1%,1/16W,G,SMD0402 | PANASONIC INDUSTRIAL CO.,LTD. | ERJ2RKF56R0X |  |  |  |  |  |  |  |  |  |
|  |  |  |  | 317 | 317 | 61100LV00-017-G |  | RES,10KOhm,+/-1%,1/16W,G,SMD0402 | KOA SPEER ELECTRONICS, INC. | RN731ETTP1002F50 | 9 |  | R940,R966,R998,R999,R1084,R1085,R1088,R1261,R1751 |  |  |  |  |  |  |
|  |  |  |  | 318 | 318 | 610114U00-017-G |  | RES,3.3KOhm,+/-1%,1/16W,G,SMD0402 | KOA SPEER ELECTRONICS, INC. | RK73H1ETTP3301F | 25 |  | R960,R1323,R1325,R1327,R1328,R1412,R1413,R1414,R1416,R1417,R1418,R1422,R1423,R1424,R1425,R1426,R1427,R1428,R1505,R1506,R1516,R1517,R1518,R1523,R1783 |  |  |  |  |  |  |
|  |  |  |  |  | 318 | 610114U00-024-G |  | RES,3.3KOhm,+/-1%,1/16W,G,SMD0402 | PANASONIC INDUSTRIAL CO.,LTD. | ERJ2RKF3301X |  |  |  |  |  |  |  |  |  |
|  |  |  |  | 319 | 319 | 61100C600-017-G |  | RES,1KOhm,+/-0.5%,1/16W,G,SMD0402 | KOA SPEER ELECTRONICS, INC. | RN731ETTP1001D25 | 19 |  | R961,R962,R963,R964,R965,R967,R968,R969,R970,R975,R976,R977,R978,R985,R986,R988,R989,R992,R1003 |  |  |  |  |  |  |
|  |  |  |  |  | 319 | 61100C600-024-G |  | RES,1KOhm,+/-0.5%,1/16W,G,SMD0402 | PANASONIC INDUSTRIAL CO.,LTD. | ERA2AED1001X |  |  |  |  |  |  |  |  |  |
|  |  |  |  |  | 319 | 61100C600-029-G |  | RES,1KOhm,+/-0.5%,1/16W,G,SMD0402 | VISHAY ENTER TECHNO LOGY.INC | MCS04020D1001DE000 |  |  |  |  |  |  |  |  |  |
|  |  |  |  | 320 | 320 | 61010A000-017-G |  | RES,8.2KOhm,+/-5%,1/16W,G,SMD0402 | KOA SPEER ELECTRONICS, INC. | RK73B1ETTP822J | 1 |  | R971 |  |  |  |  |  |  |
|  |  |  |  |  | 320 | 61010A000-024-G |  | RES,8.2KOhm,+/-5%,1/16W,G,SMD0402 | PANASONIC INDUSTRIAL CO.,LTD. | ERJ2GEJ822X |  |  |  |  |  |  |  |  |  |
|  |  |  |  | 321 | 321 | 610115V00-017-G |  | RES,300 Ohm,+/-1%,1/16W,G,SMD0402 | KOA SPEER ELECTRONICS, INC. | RK73H1ETTP3000F | 48 |  | R991,R1440,R1446,R1447,R1448,R1449,R1450,R1451,R1594,R1595,R1596,R1597,R1598,R1601,R1602,R1607,R1608,R1609,R1610,R1611,R1612,R1613,R1614,R1615,R1616,R1617,R1618,R1619,R1620,R1621,R1622,R1623,R1624,R1625,R1626,R1627,R1628,R1629,R1630,R1631,R1632,R1633,R1634,R1635,R1636,R1637,R1638,R1723 |  |  |  |  |  |  |
|  |  |  |  | 322 | 322 | 610118100-017-G |  | RES,1.4KOhm,+/-1%,1/16W,G,SMD0402 | KOA SPEER ELECTRONICS, INC. | RK73H1ETTP1401F | 2 |  | R1000,R1002 |  |  |  |  |  |  |
|  |  |  |  |  | 322 | 610118100-024-G |  | RES,1.4KOhm,+/-1%,1/16W,G,SMD0402 | PANASONIC INDUSTRIAL CO.,LTD. | ERJ2RKF1401X |  |  |  |  |  |  |  |  |  |
|  |  |  |  | 323 | 323 | 610114R00-017-G |  | RES,49.9KOhm,+/-1%,1/16W,G,SMD0402 | KOA SPEER ELECTRONICS, INC. | RK73H1ETTP4992F | 1 |  | R1026 |  |  |  |  |  |  |
|  |  |  |  |  | 323 | 610114R00-029-G |  | RES,49.9KOhm,+/-1%,1/16W,G,SMD0402 | VISHAY ENTER TECHNO LOGY.INC | CRCW040249K9FKED |  |  |  |  |  |  |  |  |  |
|  |  |  |  | 324 | 324 | 610115W00-017-G |  | RES,18KOhm,+/-1%,1/16W,G,SMD0402 | KOA SPEER ELECTRONICS, INC. | RK73H1ETTP1802F | 1 |  | R1027 |  |  |  |  |  |  |
|  |  |  |  |  | 324 | 610115W00-024-G |  | RES,18KOhm,+/-1%,1/16W,G,SMD0402 | PANASONIC INDUSTRIAL CO.,LTD. | ERJ2RKF1802X |  |  |  |  |  |  |  |  |  |
|  |  |  |  | 325 | 325 | 610158800-017-G |  | RES,191 Ohm,+/-0.1%,1/16W,G,SMD0402 | KOA SPEER ELECTRONICS, INC. | RN731ETTP1910B25 | 3 |  | R1074,R1083,R1777 |  |  |  |  |  |  |
|  |  |  |  | 326 | 326 | 61011GN00-017-G |  | RES,1.6KOhm,+/-1%,1/16W,G,SMD0402 | KOA SPEER ELECTRONICS, INC. | RK73H1ETTP1601F | 1 |  | R1089 |  |  |  |  |  |  |
|  |  |  |  | 327 | 327 | 61100QH00-017-G |  | RES,510 Ohm,+/-0.1%,1/16W,G,SMD0402 | KOA SPEER ELECTRONICS, INC. | RN731ETTP5100B25 | 6 |  | R1092,R1093,R1110,R1113,R1114,R1115 |  |  |  |  |  |  |
|  |  |  |  | 328 | 328 | 610118400-017-G |  | RES,27 Ohm,+/-1%,1/16W,G,SMD0402 | KOA SPEER ELECTRONICS, INC. | RK73H1ETTP27R0F | 10 |  | R1094,R1095,R1096,R1097,R1098,R1104,R1105,R1106,R1108,R1109 |  |  |  |  |  |  |
|  |  |  |  | 329 | 329 | 610112800-017-G |  | RES,6.04KOhm,+/-1%,1/16W,G,SMD0402 | KOA SPEER ELECTRONICS, INC. | RK73H1ETTP6041F | 1 |  | R1147 |  |  |  |  |  |  |
|  |  |  |  |  | 329 | 610112800-029-G |  | RES,6.04KOhm,+/-1%,1/16W,G,SMD0402 | VISHAY ENTER TECHNO LOGY.INC | CRCW04026K04FKED |  |  |  |  |  |  |  |  |  |
|  |  |  |  | 330 | 330 | 610103300-017-G |  | RES,100KOhm,+/-5%,1/16W,G,SMD0402 | KOA SPEER ELECTRONICS, INC. | RK73B1ETTP104J | 6 |  | R1251,R1252,R1253,R1254,R1395,R1398 |  |  |  |  |  |  |
|  |  |  |  |  | 330 | 610103300-029-G |  | RES,100KOhm,+/-5%,1/16W,G,SMD0402 | VISHAY ENTER TECHNO LOGY.INC | CRCW0402100KJNED |  |  |  |  |  |  |  |  |  |
|  |  |  |  | 331 | 331 | 61100FR00-017-G |  | RES,13KOhm,+/-1%,1/16W,G,SMD0402 | KOA SPEER ELECTRONICS, INC. | RN731ETTP1302F25 | 1 |  | R1255 |  |  |  |  |  |  |
|  |  |  |  | 332 | 332 | 61100BK00-017-G |  | RES,47KOhm,+/-1%,1/16W,G,SMD0402 | KOA SPEER ELECTRONICS, INC. | RN731ETTP4702F25 | 1 |  | R1262 |  |  |  |  |  |  |
|  |  |  |  | 333 | 333 | 610112N00-017-G |  | RES,130 Ohm,+/-1%,1/16W,G,SMD0402 | KOA SPEER ELECTRONICS, INC. | RK73H1ETTP1300F | 1 |  | R1280 |  |  |  |  |  |  |
|  |  |  |  |  | 333 | 610112N00-029-G |  | RES,130 Ohm,+/-1%,1/16W,G,SMD0402 | VISHAY ENTER TECHNO LOGY.INC | CRCW0402130RFKED |  |  |  |  |  |  |  |  |  |
|  |  |  |  |  | 333 | 610112N00-024-G |  | RES,130 Ohm,+/-1%,1/16W,G,SMD0402 | PANASONIC INDUSTRIAL CO.,LTD. | ERJ2RKF1300X |  |  |  |  |  |  |  |  |  |
|  |  |  |  | 334 | 334 | 61011CB00-017-G |  | RES,64.9 Ohm,+/-1%,1/16W,G,SMD0402 | KOA SPEER ELECTRONICS, INC. | RK73H1ETTP64R9F | 1 |  | R1288 |  |  |  |  |  |  |
|  |  |  |  | 335 | 335 | 61010AC00-017-G |  | RES,2.2 Ohm,+/-1%,1/10W,G,SMD0603 | KOA SPEER ELECTRONICS, INC. | RK73H1JTTD2R20F | 1 |  | R1298 |  |  |  |  |  |  |
|  |  |  |  |  | 335 | 61010AC00-024-G |  | RES,2.2 Ohm,+/-1%,1/10W,G,SMD0603 | PANASONIC INDUSTRIAL CO.,LTD. | ERJ3RQF2R2V |  |  |  |  |  |  |  |  |  |
|  |  |  |  | 336 | 336 | 61100AH00-017-G |  | RES,10KOhm,+/-0.5%,1/16W,G,SMD0402 | KOA SPEER ELECTRONICS, INC. | RN731ETTP1002D25 | 8 |  | R1303,R1304,R1305,R1308,R1310,R1311,R1312,R1313 |  |  |  |  |  |  |
|  |  |  |  | 337 | 337 | 610115N00-017-G |  | RES,2.4KOhm,+/-1%,1/16W,G,SMD0402 | KOA SPEER ELECTRONICS, INC. | RK73H1ETTP2401F | 2 |  | R1331,R1332 |  |  |  |  |  |  |
|  |  |  |  | 338 | 338 | 61011BW00-017-G |  | RES,1.2KOhm,+/-1%,1/16W,G,SMD0402 | KOA SPEER ELECTRONICS, INC. | RK73H1ETTP1201F | 2 |  | R1393,R1394 |  |  |  |  |  |  |
|  |  |  |  | 339 | 339 | 61012LR00-017-G |  | RES,1KOhm,+/-0.5%,1/16W,G,SMD0402 | KOA SPEER ELECTRONICS, INC. | RK73H1ETTP1001D | 1 |  | R1480 |  |  |  |  |  |  |
|  |  |  |  | 340 | 340 | 61100QT01-017-G |  | RES,10 Ohm,+/-0.5%,1/16W,G,SMD0402 | KOA SPEER ELECTRONICS, INC. | RN731ETTP10R0D25 | 1 |  | R1483 |  |  |  |  |  |  |
|  |  |  |  | 341 | 341 | 61100LQ00-017-G |  | RES,20KOhm,+/-1%,1/16W,G,SMD0402 | KOA SPEER ELECTRONICS, INC. | RN731ETTP2002F50 | 1 |  | R1488 |  |  |  |  |  |  |
|  |  |  |  | 342 | 342 | 610118800-017-G |  | RES,499KOhm,+/-1%,1/8W,G,SMD0805 | KOA SPEER ELECTRONICS, INC. | RK73H2ATTD4993F | 1 |  | R1492 |  |  |  |  |  |  |
|  |  |  |  |  | 342 | 610118800-024-G |  | RES,499KOhm,+/-1%,1/8W,G,SMD0805 | PANASONIC | ERJ6ENF4993V |  |  |  |  |  |  |  |  |  |
|  |  |  |  | 343 | 343 | 61011LF00-017-G |  | RES,499KOhm,+/-1%,1/16W,G,SMD0402 | KOA SPEER ELECTRONICS, INC. | RK73H1ETTP4993F | 1 |  | R1493 |  |  |  |  |  |  |
|  |  |  |  |  | 343 | 61011LF00-024-G |  | RES,499KOhm,+/-1%,1/16W,G,SMD0402 | PANASONIC | ERJ2RKF4993X |  |  |  |  |  |  |  |  |  |
|  |  |  |  | 344 | 344 | 61011HC00-017-G |  | RES,2.7KOhm,+/-1%,1/16W,G,SMD0402 | KOA SPEER ELECTRONICS, INC. | RK73H1ETTP2701F | 1 |  | R1754 |  |  |  |  |  |  |
|  |  |  |  |  | 344 | 61011HC00-029-G |  | RES,2.7KOhm,+/-1%,1/16W,G,SMD0402 | VISHAY ENTER TECHNO LOGY.INC | CRCW04022K70FKED |  |  |  |  |  |  |  |  |  |
|  |  |  |  |  | 344 | 61011HC00-024-G |  | RES,2.7KOhm,+/-1%,1/16W,G,SMD0402 | PANASONIC INDUSTRIAL CO.,LTD. | ERJ2RKF2701X |  |  |  |  |  |  |  |  |  |
|  |  |  |  | 345 | 345 | 41050W700-46Y-G |  | Flash,AT45DB081E-SHNHC-T,1.65~3.6V,8M,SPI,G,SOIC-8,SMD | Adesto Technologies Corporation | AT45DB081E-SHNHC-T | 1 |  | U_LOM1_ROM1 |  |  |  |  |  |  |
|  |  |  |  | 346 | 346 | 31050KS00-185-G |  | IC,Buffer,NC7SV17P5X,0.9V~3.6V,G,SC70-5,SMD | FAIRCHILD SEMICONDUCTOR CORP | NC7SV17P5X | 2 |  | U2,U11 |  |  |  |  |  |  |
|  |  |  |  | 347 | 347 | 320242G00-183-G |  | IC,Power Controller,LM3880MFX-1AA/NOPB,G,SOT-23-6,SMD | TEXAS INSTRUMENTS | LM3880MFX-1AA/NOPB | 2 |  | U3,U4 |  |  |  |  |  |  |
|  |  |  |  | 348 | 348 | 320245T00-183-G |  | IC,Power Controller,UCD90160RGCR-C09,G,VQFN-64,SMD | TEXAS INSTRUMENTS | UCD90160RGCR-C09 | 1 |  | U5 |  |  |  |  |  |  |
|  |  |  |  | 349 | 349 | 310502800-031-G |  | IC,Buffer,74LVC1G07GW,1.65~5.5V,G,SOT353-5,SMD | NXP SEMICONDUCTORS | 74LVC1G07GW | 25 |  | U6,U7,U8,U9,U53,U54,U56,U57,U58,U59,U64,U65,U67,U69,U70,U71,U72,U85,U88,U111,U113,U114,U115,U117,U169 |  |  |  |  |  |  |
|  |  |  |  | 350 | 350 | 310406Q00-031-G |  | IC,Multiplexer,CBTL01023GM,3V~3.6V,G,XQFN-10,SMD | NXP SEMICONDUCTORS | CBTL01023GM | 1 |  | U12 |  |  |  |  |  |  |
|  |  |  |  | 351 | 351 | 21040M500-283-G |  | IC,BROADCOM,BCM54612EB1KMLG,B1,G,MLP-48,SMD | BROADCOM SINGAPORE PTE LTD. | BCM54612EB1KMLG | 1 |  | U13 |  |  |  |  |  |  |
|  |  |  |  | 352 | 352 | 21012NJ00-687-G |  | IC,ASPEED,AST2500A2-GP,A2,G,TFBGA-456,SMD | ASPEED TECHNOLOGY INC | AST2500A2-GP | 1 |  | U14 |  |  |  |  |  |  |
|  |  |  |  | 353 | 353 | 31030CA00-031-G |  | IC,Switch,PCA9546APW,2.3~5.5V,G,TSSOP-16,SMD | NXP SEMICONDUCTORS | PCA9546APW | 2 |  | U15,U16 |  |  |  |  |  |  |
|  |  |  |  | 354 | 354 | 420212A00-216-G |  | DRAM,MT40A512M16JY-083E:B,1.2V,512M*16,1.2GHz,G,FBGA-96,SMD | MICRON SEMICONDUCTOR ASIA PTE.LTD. | MT40A512M16JY-083E:B | 1 |  | U17 |  |  |  |  |  |  |
|  |  |  |  | 355 | 355 | 310311G00-183-G |  | IC,Switch,TS3L110RGYR,3V~3.6V,G,VQFN-16,SMD | TEXAS INSTRUMENTS | TS3L110RGYR | 2 |  | U18,U19 |  |  |  |  |  |  |
|  |  |  |  | 356 | 356 | 410512F00-233-G |  | Flash,MX66L51235FMI-10G,2.7V~3.6V,512M,SPI,G,SOP-16,SMD | MACRONIX INTERNATIONAL CO.,LTD. | MX66L51235FMI-10G | 2 |  | U20,U21 |  |  |  |  |  |  |
|  |  |  |  | 357 | 357 | 41050DL00-233-G |  | Flash,MX25L6445EMI-10G,2.7~3.6V,64M,SPI,G,SOP-16,SMD | MACRONIX INTERNATIONAL CO.,LTD. | MX25L6445EMI-10G | 1 |  | U24 |  |  |  |  |  |  |
|  |  |  |  | 358 | 358 | 310312S00-217-G |  | IC,Switch,74CBTLV3125QG8,2.3V~3.6V,G,QSOP-16,SMD | INTEGRATED DEVICE TECHNOLOGY | 74CBTLV3125QG8 | 1 |  | U25 |  |  |  |  |  |  |
|  |  |  |  | 359 | 359 | 310408900-217-G |  | IC,Switch,74CBTLV3257PGG8,2.3~3.6V,G,TSSOP-16,SMD | INTEGRATED DEVICE TECHNOLOGY | 74CBTLV3257PGG8 | 2 |  | U27,U179 |  |  |  |  |  |  |
|  |  |  |  | 360 | 360 | 21050F900-217-G |  | IC,IDT,2305B-1DCG8,B,G,SOIC-8,SMD | INTEGRATED DEVICE TECHNOLOGY | 2305B-1DCG8 | 1 |  | U29 |  |  |  |  |  |  |
|  |  |  |  | 361 | 361 | 41040BT00-191-G |  | EEPROM,AT24C64D-SSHM-T,1.7~5.5V,64K,I2C,G,SOIC-8,SMD | ATMEL CORPORATION | AT24C64D-SSHM-T | 1 |  | U30 |  |  |  |  |  |  |
|  |  |  |  | 362 | 362 | 320501P00-173-G |  | IC,Driver/Receiver,MAX3243CAI+T,G,SSOP-28,SMD | MAXIM INTEGRATED PRODUCTS, INC. | MAX3243CAI+T | 1 |  | U32 |  |  |  |  |  |  |
|  |  |  |  | 363 | 363 | 21081AQ00-426-G |  | IC,RENESAS,uPD720201K8-701-BAC-A,G,QFN-68,SMD | RENESAS TECHNOLOGY AMERICA INC | uPD720201K8-701-BAC-A | 1 |  | U36 |  |  |  |  |  |  |
|  |  |  |  | 364 | 364 | 41050J100-233-G |  | Flash,MX25L5121EMC-20G,2.7~3.6V,512K,SPI,G,SOP-8,SMD | MACRONIX INTERNATIONAL CO.,LTD. | MX25L5121EMC-20G | 1 |  | U37 |  |  |  |  |  |  |
|  |  |  |  | 365 | 365 | 210826400-183-G |  | IC,TI,TUSB2077APTR,G,LQFP-48,SMD | TEXAS INSTRUMENTS | TUSB2077APTR | 1 |  | U38 |  |  |  |  |  |  |
|  |  |  |  | 366 | 366 | 21081N000-348-G |  | IC,MARVELL,88SE9235A1-NAA2C000,A1,G,QFN-76,SMD | MARVELL SEMICONDUCTOR, INC | 88SE9235A1-NAA2C000[VER.A1] | 1 |  | U45 |  |  |  |  |  |  |
|  |  |  |  | 367 | 367 | 41050K700-233-G |  | Flash,MX25L4006EM2I-12G,2.7V~3.6V,4M,SPI,G,SOP-8,SMD | MACRONIX INTERNATIONAL CO.,LTD. | MX25L4006EM2I-12G | 1 |  | U46 |  |  |  |  |  |  |
|  |  |  |  | 368 | 368 | 310203000-031-G |  | IC,Trigger,74LVC74APW,1.2~3.6V,G,TSSOP-14,SMD | NXP SEMICONDUCTORS | 74LVC74APW | 2 |  | U55,U168 |  |  |  |  |  |  |
|  |  |  |  | 369 | 369 | 21050P200-031-G |  | IC,NXP,PCF8523TK,G,HVSON-8,SMD | NXP SEMICONDUCTORS | PCF8523TK | 1 |  | U60 |  |  |  |  |  |  |
|  |  |  |  | 370 | 370 | 21050Q600-217-G |  | IC,IDT,5PB1102PGGI8,G,TSSOP-8,SMD | INTEGRATED DEVICE TECHNOLOGY | 5PB1102PGGI8 | 1 |  | U61 |  |  |  |  |  |  |
|  |  |  |  | 371 | 371 | SI5338C-B06799-GMR |  | IC,SILABS,Si5338C-B06799-GMR,G,QFN-24,SMD | Silicon Laboratories Inc. | SI5338C-B06799-GMR | 1 |  | U62 |  |  |  |  |  |  |
|  |  |  |  | 372 | 372 | 21050P100-217-G |  | IC,IDT,9DBL0452BKILFT,G,VFQFPN-32,SMD | INTEGRATED DEVICE TECHNOLOGY | 9DBL0452BKILFT | 1 |  | U63 |  |  |  |  |  |  |
|  |  |  |  | 373 | 373 | 310101400-031-G |  | IC,Gate&Inverter,74LVC1G08GW,1.65~5.5V,G,SOT353-5,SMD | NXP SEMICONDUCTORS | 74LVC1G08GW | 13 |  | U66,U73,U74,U75,U76,U77,U78,U79,U80,U81,U82,U161,U178 |  |  |  |  |  |  |
|  |  |  |  | 374 | 374 | 310504B00-031-G |  | IC,Buffer,74LVC1G17GW,1.65~5.5V,G,SOT353-5,SMD | NXP SEMICONDUCTORS | 74LVC1G17GW | 3 |  | U68,U86,U89 |  |  |  |  |  |  |
|  |  |  |  | 375 | 375 | 310500F00-031-G |  | IC,Buffer,74LVC07APW,1.65~5.5V,G,TSSOP-14,SMD | NXP SEMICONDUCTORS | 74LVC07APW | 3 |  | U83,U101,U102 |  |  |  |  |  |  |
|  |  |  |  | 376 | 376 | 320231500-183-G |  | IC,Voltage Sensor,TPS3897ADRYR,G,SON-6,SMD | TEXAS INSTRUMENTS | TPS3897ADRYR | 1 |  | U84 |  |  |  |  |  |  |
|  |  |  |  | 377 | 377 | 32020LS00-183-G |  | IC,Power Controller,TPS3801K33DCKR,G,SC-70-5,SMD | TEXAS INSTRUMENTS | TPS3801K33DCKR | 1 |  | U87 |  |  |  |  |  |  |
|  |  |  |  | 378 | 378 | 310201900-031-G |  | IC,Gate&Inverter,74LVC2G14GW,1.65~5.5V,G,SOT363-6,SMD | NXP SEMICONDUCTORS | 74LVC2G14GW | 3 |  | U90,U91,U112 |  |  |  |  |  |  |
|  |  |  |  | 379 | 379 | 31050J800-031-G |  | IC,Buffer,PCA9516APW,2.3V~3.6V,G,TSSOP-16,SMD | NXP SEMICONDUCTORS | PCA9516APW | 4 |  | U92,U93,U94,U95 |  |  |  |  |  |  |
|  |  |  |  | 380 | 380 | 32021R100-252-G |  | IC,Power Controller,PI3USB102ZLEX,G,TQFN-10P,SMD | PERICOM SEMICONDUCTOR CORP | PI3USB102ZLEX | 2 |  | U96,U108 |  |  |  |  |  |  |
|  |  |  |  | 381 | 381 | 31090C800-031-G |  | IC,Transceiver,74AVC4TD245GU,0.8V~3.6V,G,XQFN-16,SMD | NXP SEMICONDUCTORS | 74AVC4TD245GU | 1 |  | U97 |  |  |  |  |  |  |
|  |  |  |  | 382 | 382 | 410403P00-214-G |  | EEPROM,M24512-WMN6TP,2.5~5.5V,512K,I2C,G,SO-8,SMD | ST MICRO ELECTRONICS,INC | M24512-WMN6TP | 1 |  | U98 |  |  |  |  |  |  |
|  |  |  |  | 383 | 383 | 210203M00-031-G |  | IC,NXP,PCA9554PW,G,TSSOP-16,SMD | NXP SEMICONDUCTORS | PCA9554PW | 2 |  | U99,U100 |  |  |  |  |  |  |
|  |  |  |  | 384 | 384 | 311004800-031-G |  | IC,Translator,PCA9617ADPJ,0.8~5.5V,2.2~5.5V,G,TSSOP-8,SMD | NXP SEMICONDUCTORS | PCA9617ADPJ | 4 |  | U104,U105,U106,U107 |  |  |  |  |  |  |
|  |  |  |  | 385 | 385 | 310307T00-031-G |  | IC,Switch,74CBTLV1G125GV,2.3~3.6V,G,SOT753-5,SMD | NXP SEMICONDUCTORS | 74CBTLV1G125GV | 1 |  | U109 |  |  |  |  |  |  |
|  |  |  |  | 386 | 386 | 330103N00-426-G |  | IC,Optocoupler,PS2811-1-F3-A,G,SSOP-4,SMD | RENESAS TECHNOLOGY AMERICA INC | PS2811-1-F3-A | 1 |  | U110 |  |  |  |  |  |  |
|  |  |  |  | 387 | 387 | 21081WR00-031-G |  | IC,NXP,PCA9541APW/01,G,TSSOP-16,SMD | NXP SEMICONDUCTORS | PCA9541APW/01 | 1 |  | U116 |  |  |  |  |  |  |
|  |  |  |  | 388 | 388 | 311006F00-031-G |  | IC,Translator,PCA9508D,0.9V~5.5V/2.7V~5.5V,G,SO-8,SMD | NXP SEMICONDUCTORS | PCA9508D | 1 |  | U164 |  |  |  |  |  |  |
|  |  |  |  | 389 | 389 | 320242H00-226-G |  | IC,Power Controller,LTC2955CDDB-2#TRMPBF,G,DFN-10,SMD | LINEAR TECHNOLOGY CORPORATION | LTC2955CDDB-2#TRMPBF | 1 |  | U165 |  |  |  |  |  |  |
|  |  |  |  | 390 | 390 | 32050Q900-031-G |  | IC,LED Driver,PCA9551PW,G,TSSOP-16,SMD | NXP SEMICONDUCTORS | PCA9551PW | 2 |  | U166,U172 |  |  |  |  |  |  |
|  |  |  |  | 391 | 391 | 310203U00-223-G |  | IC,Trigger,NL17SZ14DFT2G,1.65~5.5V,G,SOT353-5,SMD | ON SEMICONDUCTOR CORP | NL17SZ14DFT2G | 2 |  | U167,U173 |  |  |  |  |  |  |
|  |  |  |  | 392 | 392 | 310109D00-031-G |  | IC,Gate&Inverter,74LVC1G32GW,1.65~5.5V,G,TSSOP-5,SMD | NXP SEMICONDUCTORS | 74LVC1G32GW | 3 |  | U170,U174,U180 |  |  |  |  |  |  |
|  |  |  |  | 393 | 393 | 31050KL00-031-G |  | IC,Buffer,74HC75PW,2.0V~6.0V,G,TSSOP-16,SMD | NXP SEMICONDUCTORS | 74HC75PW | 1 |  | U171 |  |  |  |  |  |  |
|  |  |  |  | 394 | 394 | 31010SB00-183-G |  | Logic IC,Gate,ISO1540DR,3V~5.5V,G,SOIC-8,SMD | TEXAS INSTRUMENTS | ISO1540DR | 1 |  | U175 |  |  |  |  |  |  |
|  |  |  |  | 395 | 395 | 71011RD00-100-G |  | XTAL,25MHz,+/-25ppm,20pF,G,SMD | TXC CORPORATION | 7V25000016 | 1 |  | X1 |  |  |  |  |  |  |
|  |  |  |  | 396 | 396 | 71010SY00-107-G |  | XTAL,25MHz,+/-30ppm,20pF,G,SMD | DAISHINKU CORPORATION/DAISHINKU SINGAPORE PTE LTD/KDS | 1Y725000CC1G | 1 |  | X2 |  |  |  |  |  |  |
|  |  |  |  | 397 | 397 | 710113800-100-G |  | XTAL,24MHz,+/-30ppm,20pF,G,SMD | TXC CORPORATION | 7B24000038 | 1 |  | X3 |  |  |  |  |  |  |
|  |  |  |  | 398 | 398 | 71012EC00-162-G |  | XTAL,6MHz,+/-30ppm,20pF,G,SMD | EPSON ELECTRONICS AMERICA,INC. | Q22MA4061164200 | 1 |  | X4 |  |  |  |  |  |  |
|  |  |  |  | 399 | 399 | 71011UL00-107-G |  | XTAL,25MHz,+/-15ppm,16pF,G,SMD | DAISHINKU CORPORATION/DAISHINKU SINGAPORE PTE LTD/KDS | 1ZHY25000BB0A | 1 |  | X5 |  |  |  |  |  |  |
|  |  |  |  | 400 | 400 | 710106900-162-G |  | XTAL,32.768KHz,+/-20ppm,12.5pF,G,SMD | EPSON ELECTRONICS AMERICA,INC. | Q13FC1350000400 | 1 |  | X6 |  |  |  |  |  |  |
|  |  |  |  | 401 | 401 | 71020SC00-107-G |  | OSC,24MHz,+/-25ppm,3.3V,15pF,G,SMD | DAISHINKU CORPORATION/DAISHINKU SINGAPORE PTE LTD/KDS | 1XSE024000AR40 | 1 |  | Y1 |  |  |  |  |  |  |
|  |  |  |  | 402 | 402 | 71020Q600-16G-G |  | OSC,50MHz,50ppm,3.3V,G,SMD | SiTime Corporation | SIT1602AC-23-33E-50.000000T | 1 |  | Y2 |  |  |  |  |  |  |
|  |  |  |  | 403 | 403 | 710213J00-16G-G |  | OSC,25MHz,+/-1.5ppm,3.3V,15pF,G,SMD | SiTime Corporation | SIT5000AC-3B-33N0-25.000000T | 1 |  | Y3 |  |  |  |  |  |  |
|  |  |  |  | 404 | 404 | 71020KL00-100-G |  | OSC,33MHz,+/-50ppm,3.3V,15pF,G,SMD | TXC CORPORATION | 7X33000013 | 1 |  | Y4 |  |  |  |  |  |  |
|  |  |  |  | 405 | 405 | 340660600-GRS-G |  | CONN,Header,Battery Holder,Bla,21.3mm,G/F,G,SMD-2 | LOTES CO LTD | AAA-BAT-063-P02_A | 1 |  | B1 |  |  |  |  |  |  |
|  |  |  |  | 406 | 406 | 2T714BY00-086-G |  | Fuse Clips,N/A,7.87mm*7.11mm10.67mm,G,00 | LITTELFUSE FAR EAST PTE LTD | 01220088Z | 8 |  | CLIP1,CLIP2,CLIP3,CLIP4,CLIP5,CLIP6,PSUCLIP1,PSUCLIP2 |  |  |  |  |  |  |
|  |  |  |  | 407 | 407 | 34021BC00-G78-G |  | CONN,DDR IV,V/T,1.2V,Blu,0.85mm,15u,G,SMD-288 | FCI CONNECTORS HONGKONG LTD. | 10140702-0302K11LF | 16 |  | DIMM02,DIMM04,DIMM06,DIMM09,DIMM11,DIMM13,DIMM15,DIMM16,DIMM18,DIMM20,DIMM22,DIMM25,DIMM27,DIMM29,DIMM31,DIMM00 |  |  |  |  |  |  |
|  |  |  |  | 408 | 408 | 34021BD00-G78-G |  | CONN,DDR IV,V/T,1.2V,Bla,0.85mm,15u,G,SMD-288 | FCI CONNECTORS HONGKONG LTD. | 10140702-0301K11LF | 16 |  | DIMM01,DIMM03,DIMM05,DIMM07,DIMM08,DIMM10,DIMM12,DIMM14,DIMM17,DIMM19,DIMM21,DIMM23,DIMM24,DIMM26,DIMM28,DIMM30 |  |  |  |  |  |  |
|  |  |  |  | 409 | 409 | 340612R00-309-G |  | CONN,Jumper,Bla,2.54mm,G,DIP-2 | SAMTEC INC. | SNT-100-BK-G | 3 |  | JP1(2-3),JP4(2-3),JP5(2-3) |  |  |  |  |  |  |
|  |  |  |  |  | 409 | 34065L900-GRT-G |  | CONN,jumper,Bla,2.54mm,30u,G,DIP-2 | PINREX TECHNOLOGY CORP. | 201-71-01DB00 |  |  |  |  |  |  |  |  |  |
|  |  |  |  | 410 | 410 | 34068LN00-317-G |  | CONN,Header,Pin Header,1X3,V/T,2.54mm,30u,G,SMD-3 | MOLEX INCORPORATED | 87898-0315 | 11 |  | J_BMC_DEBUG1,J1,J3,J4,J5,J7,J36,J41,J43,J48,J147 |  |  |  |  |  |  |
|  |  |  |  | 411 | 411 | 340692800-309-G |  | CONN,Header,Socket,2X30,V/T,Bla,0.5mm,G/F,G,SMD-60 | SAMTEC INC. | QSH-030-01-F-D-A-K-TR | 2 |  | J2,J6 |  |  |  |  |  |  |
|  |  |  |  | 412 | 412 | 340459T00-GRS-G |  | CONN,I/O,HDMI,V/T,Bla,0.5mm,1u,G,SMD-19 | LOTES CO LTD | AHDM0001-P004A | 1 |  | J8 |  |  |  |  |  |  |
|  |  |  |  | 413 | 413 | 3406A2A00-309-G |  | CONN,Header,Shrouded,2X4,V/T,1.27mm,15u,G,SMD-8 | SAMTEC INC. | TFM-104-02-L-D-K-TR | 1 |  | J9 |  |  |  |  |  |  |
|  |  |  |  | 414 | 414 | 3406A2C00-309-G |  | CONN,Header,Shrouded,2X6,V/T,1.27mm,15u,G,SMD-12 | SAMTEC INC. | TFM-106-02-L-D-K-TR | 1 |  | J10 |  |  |  |  |  |  |
|  |  |  |  | 415 | 415 | 3406AEU00-245-G |  | CONN,Header,Shrouded,2X4,R/A,Bla,2.54mm,G/F,G,DIP-8 | AMPHENOL SHANGHAI CORP. | G821EU208AGN00Y | 1 |  | J11 |  |  |  |  |  |  |
|  |  |  |  | 416 | 416 | 34071AW00-245-G |  | CONN,SATA,V/T,Bla,1.27mm,15u,G,DIP-22 | AMPHENOL SHANGHAI CORP. | G16CE41210W3EU | 1 |  | J14 |  |  |  |  |  |  |
|  |  |  |  | 417 | 417 | 34031RP00-600-G |  | CONN,NGFF,R/A,Bla,0.5mm,30u,G,SMD-67 | FOXCONN TECHNOLOGY CO.,LTD. | 2E0BC23-S85BM-7H | 1 |  | J15 |  |  |  |  |  |  |
|  |  |  |  | 418 | 418 | 34131WS00-G78-G |  | CONN,BTB,Bla,0.8mm,7.87u,G,SMD-120 | FCI CONNECTORS HONGKONG LTD. | 10139781-122402LF | 1 |  | J16 |  |  |  |  |  |  |
|  |  |  |  | 419 | 419 | 34131WT00-G78-G |  | CONN,BTB,Bla,0.8mm,7.87u,G,SMD-80 | FCI CONNECTORS HONGKONG LTD. | 10139781-082402LF | 2 |  | J17,J18 |  |  |  |  |  |  |
|  |  |  |  | 420 | 420 | 340604M00-600-G |  | CONN,Header,Friction,1X3,V/T,Ivo,2.54mm,G,DIP-3 | FOXCONN TECHNOLOGY CO.,LTD. | HF2803E-P1 | 4 |  | J19,J20,J21,J22 |  |  |  |  |  |  |
|  |  |  |  | 421 | 421 | 3406A2B00-317-G |  | CONN,Header,WTB,1X4,V/T,Bla,2.54mm,15u,G,DIP-4 | MOLEX INCORPORATED | 171856-1104 | 4 |  | J23,J24,J25,J26 |  |  |  |  |  |  |
|  |  |  |  | 422 | 422 | 3406AMV00-317-G |  | CONN,Header,MINFIT,2X4,V/T,Bla,10mm,30u,G,DIP-8 | MOLEX INCORPORATED | 42819-4233 | 1 |  | J27 |  |  |  |  |  |  |
|  |  |  |  | 423 | 423 | 34071BE00-317-G |  | CONN,SATA,V/T,Bla,1.27mm,15u,G,DIP-7 | MOLEX INCORPORATED | 678008025 | 4 |  | J29,J32,J49,J50 |  |  |  |  |  |  |
|  |  |  |  | 424 | 424 | 34062MW00-309-G |  | CONN,Header,WTB,2X5,V/T,Bla,1.27mm,10u,G,SMD-10 | SAMTEC INC. | FTSH-105-01-L-DV-K-P-TR | 2 |  | J_JTAG_LOM1,J101 |  |  |  |  |  |  |
|  |  |  |  | 425 | 425 | 3406AQH00-317-G |  | CONN,Header,Pin Header,1X6,V/T,Bla,2.54mm,G,SMD-6 | MOLEX INCORPORATED | 87898-0656 | 5 |  | J35,J37,J39,J42,J45 |  |  |  |  |  |  |
|  |  |  |  | 426 | 426 | 34051FE00-GRS-G |  | CONN,Modular Jack,USBX2_RJ45,R/A,Bla/Blu,2mm,30u,G,DIP-23 | LOTES CO LTD | AUSBS002-K001C05 | 1 |  | J99 |  |  |  |  |  |  |
|  |  |  |  | 427 | 427 | 3406ARP00-317-G |  | CONN,Header,Power,2X8,V/T,Whi,4.2mm,G,DIP-16 | MOLEX INCORPORATED | 46015-1602 | 1 |  | J100 |  |  |  |  |  |  |
|  |  |  |  | 428 | 428 | 3406AUA00-309-G |  | CONN,Pin Header,1X2,V/T,Bla,2.54mm,10u,G,SMD-2 | SAMTEC INC. | ASP-195607-01 | 36 |  | J105,J106,J107,J108,J109,J110,J111,J112,J113,J114,J115,J116,J118,J119,J120,J121,J122,J123,J124,J126,J127,J128,J129,J130,J131,J132,J133,J134,J135,J136,J137,J138,J139,J140,J141,J149 |  |  |  |  |  |  |
|  |  |  |  | 429 | 429 | 340672300-317-G |  | CONN,Pin Header,1X4,V/T,Bla,2.54mm,30u,G,SMD-4 | MOLEX INCORPORATED | 87898-0455 | 1 |  | J148 |  |  |  |  |  |  |
|  |  |  |  | 430 | 430 | 34050PV00-48U-G |  | CONN,Modular Jack,RJ45X2,R/A,Bla,1.27mm,50u,G,DIP-28 | TRP CONNECTOR B.V. | 1840855-5 | 1 |  | LAN1 |  |  |  |  |  |  |
|  |  |  |  |  | 430 | 34051E700-609-G |  | CONN,Modular Jack,RJ45X2,R/A,Bla,1.27mm,50u,G,DIP-28 | U.D. Electronic Corp. | MA-FN-0003 |  |  |  |  |  |  |  |  |  |
|  |  |  |  | 431 | 431 | 340634U00-600-G |  | CONN,Pin Header,2X3,V/T,Bla,2.54mm,30u,G,SMD-6 | FOXCONN TECHNOLOGY CO.,LTD. | HS1103H-RN | 6 |  | PBMJ1,PBEJ1,PBAJ1,PAMJ1,PAEJ1,PAAJ1 |  |  |  |  |  |  |
|  |  |  |  | 432 | 432 | PI3753-00-LGIZ |  | IC,Regulator,PI3753-00,ADJ,4A,G,LGA-71,SMD | Vicor Corporation | PI3753-00-LGIZ | 2 |  | PBAU3,PAAU3 |  |  |  |  |  |  |
|  |  |  |  | 433 | 433 | PI3755-02-LGIZ |  | IC,Regulator,PI3755-02-LGIZ,ADJ,4A,G,LGA-71,SMD | Vicor Corporation | PI3755-02-LGIZ | 6 |  | PBFU3,PBEU3,PAMU3,PAFU3,PAEU3,PBMU3 |  |  |  |  |  |  |
|  |  |  |  | 434 | 434 | 10061913-102HLF |  | CONN,PCIE-8X,V/T,Bla,1mm,30u,G,SMD-98 | FCI CONNECTORS HONGKONG LTD. | 10061913-102HLF | 2 |  | PCIE1,PCIE5 |  |  |  |  |  |  |
|  |  |  |  | 435 | 435 | 10061913-103HLF |  | CONN,PCIE-16X,V/T,Bla,1mm,30u,G,SMD-164 | FCI CONNECTORS HONGKONG LTD. | 10061913-103HLF | 3 |  | PCIE2,PCIE3,PCIE4 |  |  |  |  |  |  |
|  |  |  |  | 436 | 436 | 340805A00-638-G |  | CONN,Switch,tact,50mA,12V,G,SMD-2 | E-SWITCH | TL1015AF160QG | 2 |  | SW1,SW2 |  |  |  |  |  |  |
|  |  |  |  | 437 | 437 | 34081GH00-653-G |  | CONN,Switch,tact,Brown,50mA,12V,G,DIP-4 | DIPTRONICS MANUFACTURING INC. | DTSA-644N-Q | 2 |  | SW3,SW4 |  |  |  |  |  |  |
|  |  |  |  | 438 | 438 | 340108S00-600-G |  | POWER9 CPU Socket for LGA3899-HYBRID | FOXCONN TECHNOLOGY CO.,LTD. | PE38993-51BC0-1H | 2 |  | U1,U10 |  |  |  |  |  |  |
|  |  |  |  | 439 | 439 | 34061E400-GRS-G |  | CONN,Socket,SPI Flash,V/T,Bla,1.27mm,G/F,G,SMD-16 | LOTES CO LTD | ACA-SPI-006-F01 | 2 |  | U22,U23 |  |  |  |  |  |  |
|  |  |  |  | 440 | 440 | 320245600-232-G |  | IC,Power Controller,MIC2039AYM6-TR,G,SOT-23-6,SMD | MICROCHIP | MIC2039AYM6-TR | 3 |  | U33,U35,U177 |  |  |  |  |  |  |
|  |  |  |  | 441 | 441 | 880302800-53N-G |  | Converter,input 0V~60V,131W,G,VTM48MP010C105AG0 | Vicor Corporation | VTM48MP010C105AG0 | 2 |  | PAMU4,PBMU4 |  |  |  |  |  |  |
